FILE_TYPE = MACRO_DRAWING;
SET COLOR_WIRE YELLOW;
SET COLOR_PROP ORANGE;
SET COLOR_DOT WHITE;
SET COLOR_ARC YELLOW;
SET COLOR_BODY GREEN;
SET COLOR_NOTE PURPLE;
SET PROP_DISPLAY VALUE;
SET PAGE_NUMBER P182;
FORCEADD Q_CAP..1
(13275 4275);
FORCEPROP 1 LAST PART_NUMBER CH4104K1B00
J 0
(13325 4125);
DISPLAY 0.638298 (13325 4125);
DISPLAY INVISIBLE (13325 4125);
FORCEPROP 1 LAST VALUE 0.1UF
J 0
(13325 4325);
DISPLAY 0.638298 (13325 4325);
FORCEPROP 1 LAST MATERIAL X7R
J 0
(13325 4175);
DISPLAY 0.638298 (13325 4175);
FORCEPROP 1 LAST PACK_TYPE 0402
J 0
(13325 4075);
DISPLAY 0.638298 (13325 4075);
FORCEPROP 1 LAST VOLTAGE 25V
J 0
(13325 4275);
DISPLAY 0.638298 (13325 4275);
FORCEPROP 1 LAST TOLERANCE 10%
J 0
(13325 4225);
DISPLAY 0.638298 (13325 4225);
FORCEPROP 1 LAST LOCATION C1925
J 0
(13325 4375);
DISPLAY 0.978723 (13325 4375);
FORCEPROP 1 LASTPIN (13275 4375) $PN 1
J 0
(13285 4355);
DISPLAY 0.787234 (13285 4355);
FORCEPROP 1 LASTPIN (13275 4175) $PN 2
J 0
(13285 4155);
DISPLAY 0.787234 (13285 4155);
FORCEPROP 2 LAST CDS_LIB pure_quanta
J 0
(13275 4275);
PAINT MONO (13275 4275);
DISPLAY INVISIBLE (13275 4275);
FORCEPROP 1 LAST PATH I100
J 0
(13325 4425);
DISPLAY 0.978723 (13325 4425);
PAINT WHITE (13325 4425);
DISPLAY INVISIBLE (13325 4425);
FORCEPROP 2 LAST $SEC 1
J 0
(13325 4475);
DISPLAY 0.680851 (13325 4475);
PAINT MONO (13325 4475);
DISPLAY INVISIBLE (13325 4475);
FORCEPROP 2 LAST CDS_SEC 1
J 0
(13325 4475);
DISPLAY 1.021277 (13325 4475);
DISPLAY INVISIBLE (13325 4475);
FORCEADD Q_RES..2
(13350 2900);
FORCEPROP 1 LAST PART_NUMBER CS21002FB06
J 0
(13390 2775);
DISPLAY 0.638298 (13390 2775);
DISPLAY INVISIBLE (13390 2775);
FORCEPROP 1 LAST MATERIAL CHIP
J 0
(13390 2825);
DISPLAY 0.638298 (13390 2825);
FORCEPROP 1 LAST WATTAGE 1/16W
J 0
(13390 2875);
DISPLAY 0.638298 (13390 2875);
FORCEPROP 1 LAST TOLERANCE 1%
J 0
(13395 2925);
DISPLAY 0.638298 (13395 2925);
FORCEPROP 1 LAST VALUE 1K
J 0
(13395 2975);
DISPLAY 0.638298 (13395 2975);
FORCEPROP 1 LAST PACK_TYPE 0402LF
J 0
(13390 2725);
DISPLAY 0.638298 (13390 2725);
FORCEPROP 1 LAST $LOCATION R1605
J 0
(13395 3025);
DISPLAY 0.978723 (13395 3025);
FORCEPROP 1 LASTPIN (13350 3000) $PN 1
J 0
(13355 2962);
DISPLAY 0.787234 (13355 2962);
PAINT MONO (13355 2962);
FORCEPROP 1 LASTPIN (13350 2800) $PN 2
J 0
(13355 2810);
DISPLAY 0.787234 (13355 2810);
PAINT MONO (13355 2810);
FORCEPROP 1 LAST PATH I105
J 0
(13400 3075);
DISPLAY 0.978723 (13400 3075);
PAINT WHITE (13400 3075);
DISPLAY INVISIBLE (13400 3075);
FORCEPROP 2 LAST CDS_LIB pure_quanta
J 0
(13350 2900);
PAINT MONO (13350 2900);
DISPLAY INVISIBLE (13350 2900);
FORCEPROP 2 LAST CDS_LOCATION R1605
J 0
(13400 3125);
DISPLAY 1.021277 (13400 3125);
DISPLAY INVISIBLE (13400 3125);
FORCEPROP 2 LAST $SEC 1
J 0
(13400 3125);
DISPLAY 0.680851 (13400 3125);
PAINT MONO (13400 3125);
DISPLAY INVISIBLE (13400 3125);
FORCEPROP 2 LAST CDS_SEC 1
J 0
(13400 3125);
DISPLAY 1.021277 (13400 3125);
DISPLAY INVISIBLE (13400 3125);
FORCEADD UNIVERSAL_GND..1
(13350 2650);
FORCEPROP 3 LASTPIN (13350 2700) SIG_NAME GND\g
J 0
(13360 2710);
DISPLAY 0.659574 (13360 2710);
PAINT MONO (13360 2710);
DISPLAY INVISIBLE (13360 2710);
FORCEPROP 2 LAST CDS_LIB logical_power
J 0
(13350 2650);
PAINT MONO (13350 2650);
DISPLAY INVISIBLE (13350 2650);
FORCEPROP 1 LAST PATH I106
J 0
(13425 2650);
DISPLAY 0.872340 (13425 2650);
PAINT AQUA (13425 2650);
DISPLAY INVISIBLE (13425 2650);
FORCEPROP 1 LAST HDL_POWER GND
J 1
(13375 2575);
DISPLAY 0.872340 (13375 2575);
PAINT GREEN (13375 2575);
DISPLAY INVISIBLE (13375 2575);
FORCEADD OFFPAGE..4
(10625 3750);
FORCEPROP 2 LAST $XR0 181 
J 0
(10811 3750);
DISPLAY 0.638298 (10811 3750);
PAINT MONO (10811 3750);
FORCEPROP 2 LAST CDS_LIB standard
J 0
(10625 3750);
PAINT MONO (10625 3750);
DISPLAY INVISIBLE (10625 3750);
FORCEPROP 2 LAST PATH I107
J 0
(11125 3800);
DISPLAY 1.021277 (11125 3800);
DISPLAY INVISIBLE (11125 3800);
FORCEPROP 1 LAST OFFPAGE TRUE
J 0
(10950 3625);
DISPLAY 0.872340 (10950 3625);
DISPLAY INVISIBLE (10950 3625);
FORCEPROP 1 LAST COMMENT_BODY TRUE
J 0
(10600 3650);
DISPLAY 0.872340 (10600 3650);
PAINT GREEN (10600 3650);
DISPLAY INVISIBLE (10600 3650);
FORCEADD OFFPAGE..5
(12500 3150);
FORCEPROP 2 LAST $XR0 190 
J 0
(12215 3150);
DISPLAY 0.638298 (12215 3150);
PAINT MONO (12215 3150);
FORCEPROP 2 LAST PATH I108
J 0
(13000 3200);
DISPLAY 1.021277 (13000 3200);
DISPLAY INVISIBLE (13000 3200);
FORCEPROP 2 LAST CDS_LIB standard
J 0
(12500 3150);
PAINT MONO (12500 3150);
DISPLAY INVISIBLE (12500 3150);
FORCEPROP 1 LAST OFFPAGE TRUE
J 0
(12825 3025);
DISPLAY 0.872340 (12825 3025);
DISPLAY INVISIBLE (12825 3025);
FORCEPROP 1 LAST COMMENT_BODY TRUE
J 0
(12600 3075);
DISPLAY 0.872340 (12600 3075);
PAINT GREEN (12600 3075);
DISPLAY INVISIBLE (12600 3075);
FORCEADD OFFPAGE..3
(10625 3050);
FORCEPROP 2 LAST $XR0 194 
J 0
(10839 3050);
DISPLAY 0.638298 (10839 3050);
PAINT MONO (10839 3050);
FORCEPROP 2 LAST PATH I120
J 0
(10850 3100);
DISPLAY 1.021277 (10850 3100);
DISPLAY INVISIBLE (10850 3100);
FORCEPROP 1 LAST COMMENT_BODY TRUE
J 0
(10575 2950);
DISPLAY 0.872340 (10575 2950);
PAINT GREEN (10575 2950);
DISPLAY INVISIBLE (10575 2950);
FORCEPROP 1 LAST OFFPAGE TRUE
J 0
(10950 2925);
DISPLAY 0.872340 (10950 2925);
PAINT GREEN (10950 2925);
DISPLAY INVISIBLE (10950 2925);
FORCEPROP 2 LAST CDS_LIB standard
J 0
(10625 3050);
PAINT MONO (10625 3050);
DISPLAY INVISIBLE (10625 3050);
FORCEADD OFFPAGE..1
(6475 3450);
FORCEPROP 2 LAST $XR0 190 
J 0
(6193 3450);
DISPLAY 0.638298 (6193 3450);
PAINT MONO (6193 3450);
FORCEPROP 2 LAST CDS_LIB standard
J 0
(6475 3450);
PAINT MONO (6475 3450);
DISPLAY INVISIBLE (6475 3450);
FORCEPROP 2 LAST PATH I123
J 0
(6200 3500);
DISPLAY 1.021277 (6200 3500);
DISPLAY INVISIBLE (6200 3500);
FORCEPROP 1 LAST COMMENT_BODY TRUE
J 0
(6600 3350);
DISPLAY 0.872340 (6600 3350);
PAINT GREEN (6600 3350);
DISPLAY INVISIBLE (6600 3350);
FORCEPROP 1 LAST OFFPAGE TRUE
J 0
(6800 3325);
DISPLAY 0.872340 (6800 3325);
DISPLAY INVISIBLE (6800 3325);
FORCEADD OFFPAGE..1
(6875 3550);
FORCEPROP 2 LAST $XR0 190 
J 0
(6623 3550);
DISPLAY 0.638298 (6623 3550);
PAINT MONO (6623 3550);
FORCEPROP 2 LAST CDS_LIB standard
J 0
(6875 3550);
PAINT MONO (6875 3550);
DISPLAY INVISIBLE (6875 3550);
FORCEPROP 2 LAST PATH I124
J 0
(6600 3600);
DISPLAY 1.021277 (6600 3600);
DISPLAY INVISIBLE (6600 3600);
FORCEPROP 1 LAST COMMENT_BODY TRUE
J 0
(7000 3450);
DISPLAY 0.872340 (7000 3450);
PAINT GREEN (7000 3450);
DISPLAY INVISIBLE (7000 3450);
FORCEPROP 1 LAST OFFPAGE TRUE
J 0
(7200 3425);
DISPLAY 0.872340 (7200 3425);
DISPLAY INVISIBLE (7200 3425);
FORCEADD OFFPAGE..4
(10625 3700);
FORCEPROP 2 LAST $XR0 181 
J 0
(10811 3700);
DISPLAY 0.638298 (10811 3700);
PAINT MONO (10811 3700);
FORCEPROP 2 LAST CDS_LIB standard
J 0
(10625 3700);
PAINT MONO (10625 3700);
DISPLAY INVISIBLE (10625 3700);
FORCEPROP 2 LAST PATH I125
J 0
(10825 3750);
DISPLAY 1.021277 (10825 3750);
DISPLAY INVISIBLE (10825 3750);
FORCEPROP 1 LAST COMMENT_BODY TRUE
J 0
(10600 3600);
DISPLAY 0.872340 (10600 3600);
PAINT GREEN (10600 3600);
DISPLAY INVISIBLE (10600 3600);
FORCEPROP 1 LAST OFFPAGE TRUE
J 0
(10950 3575);
DISPLAY 0.872340 (10950 3575);
DISPLAY INVISIBLE (10950 3575);
FORCEADD TAP..1
R 2
(7725 3750);
FORCEPROP 3 LASTPIN (7775 3750) SIG_NAME P3E_PCH_M2_TX_C_DP<2>
J 0
(7785 3760);
DISPLAY 0.659574 (7785 3760);
PAINT MONO (7785 3760);
DISPLAY INVISIBLE (7785 3760);
FORCEPROP 1 LASTPIN (7775 3750) BN 2
J 2
(7787 3758);
DISPLAY 0.680851 (7787 3758);
PAINT GREEN (7787 3758);
FORCEPROP 1 LAST HDL_TAP TRUE
J 2
(7400 3625);
DISPLAY 0.872340 (7400 3625);
PAINT GREEN (7400 3625);
DISPLAY INVISIBLE (7400 3625);
FORCEPROP 1 LAST BODY_TYPE PLUMBING
J 2
(7725 3800);
DISPLAY 0.872340 (7725 3800);
PAINT GREEN (7725 3800);
DISPLAY INVISIBLE (7725 3800);
FORCEPROP 2 LAST CDS_LIB standard
J 0
(7725 3750);
DISPLAY INVISIBLE (7725 3750);
FORCEPROP 1 LAST PATH I136
J 2
(7727 3750);
DISPLAY 0.872340 (7727 3750);
PAINT GREEN (7727 3750);
DISPLAY INVISIBLE (7727 3750);
FORCEADD TAP..1
R 2
(7575 3800);
FORCEPROP 3 LASTPIN (7625 3800) SIG_NAME P3E_PCH_M2_TX_C_DN<2>
J 0
(7635 3810);
DISPLAY 0.659574 (7635 3810);
PAINT MONO (7635 3810);
DISPLAY INVISIBLE (7635 3810);
FORCEPROP 1 LASTPIN (7625 3800) BN 2
J 2
(7637 3808);
DISPLAY 0.680851 (7637 3808);
PAINT GREEN (7637 3808);
FORCEPROP 1 LAST HDL_TAP TRUE
J 2
(7250 3675);
DISPLAY 0.872340 (7250 3675);
PAINT GREEN (7250 3675);
DISPLAY INVISIBLE (7250 3675);
FORCEPROP 1 LAST BODY_TYPE PLUMBING
J 2
(7575 3850);
DISPLAY 0.872340 (7575 3850);
PAINT GREEN (7575 3850);
DISPLAY INVISIBLE (7575 3850);
FORCEPROP 2 LAST CDS_LIB standard
J 0
(7575 3800);
DISPLAY INVISIBLE (7575 3800);
FORCEPROP 1 LAST PATH I137
J 2
(7577 3800);
DISPLAY 0.872340 (7577 3800);
PAINT GREEN (7577 3800);
DISPLAY INVISIBLE (7577 3800);
FORCEADD TAP..1
R 2
(7725 4000);
FORCEPROP 3 LASTPIN (7775 4000) SIG_NAME P3E_PCH_M2_TX_C_DP<1>
J 0
(7785 4010);
DISPLAY 0.659574 (7785 4010);
PAINT MONO (7785 4010);
DISPLAY INVISIBLE (7785 4010);
FORCEPROP 1 LASTPIN (7775 4000) BN 1
J 2
(7787 4008);
DISPLAY 0.680851 (7787 4008);
PAINT GREEN (7787 4008);
FORCEPROP 2 LAST CDS_LIB standard
J 0
(7725 4000);
DISPLAY INVISIBLE (7725 4000);
FORCEPROP 1 LAST BODY_TYPE PLUMBING
J 2
(7725 4050);
DISPLAY 0.872340 (7725 4050);
PAINT GREEN (7725 4050);
DISPLAY INVISIBLE (7725 4050);
FORCEPROP 1 LAST HDL_TAP TRUE
J 2
(7400 3875);
DISPLAY 0.872340 (7400 3875);
PAINT GREEN (7400 3875);
DISPLAY INVISIBLE (7400 3875);
FORCEPROP 1 LAST PATH I146
J 2
(7727 4000);
DISPLAY 0.872340 (7727 4000);
PAINT GREEN (7727 4000);
DISPLAY INVISIBLE (7727 4000);
FORCEADD TAP..1
R 2
(7575 4050);
FORCEPROP 3 LASTPIN (7625 4050) SIG_NAME P3E_PCH_M2_TX_C_DN<1>
J 0
(7635 4060);
DISPLAY 0.659574 (7635 4060);
PAINT MONO (7635 4060);
DISPLAY INVISIBLE (7635 4060);
FORCEPROP 1 LASTPIN (7625 4050) BN 1
J 2
(7637 4058);
DISPLAY 0.680851 (7637 4058);
PAINT GREEN (7637 4058);
FORCEPROP 2 LAST CDS_LIB standard
J 0
(7575 4050);
DISPLAY INVISIBLE (7575 4050);
FORCEPROP 1 LAST BODY_TYPE PLUMBING
J 2
(7575 4100);
DISPLAY 0.872340 (7575 4100);
PAINT GREEN (7575 4100);
DISPLAY INVISIBLE (7575 4100);
FORCEPROP 1 LAST HDL_TAP TRUE
J 2
(7250 3925);
DISPLAY 0.872340 (7250 3925);
PAINT GREEN (7250 3925);
DISPLAY INVISIBLE (7250 3925);
FORCEPROP 1 LAST PATH I147
J 2
(7577 4050);
DISPLAY 0.872340 (7577 4050);
PAINT GREEN (7577 4050);
DISPLAY INVISIBLE (7577 4050);
FORCEADD TAP..1
R 2
(7725 4250);
FORCEPROP 3 LASTPIN (7775 4250) SIG_NAME P3E_PCH_M2_TX_C_DP<0>
J 0
(7785 4260);
DISPLAY 0.659574 (7785 4260);
PAINT MONO (7785 4260);
DISPLAY INVISIBLE (7785 4260);
FORCEPROP 1 LASTPIN (7775 4250) BN 0
J 2
(7787 4258);
DISPLAY 0.680851 (7787 4258);
PAINT GREEN (7787 4258);
FORCEPROP 2 LAST CDS_LIB standard
J 0
(7725 4250);
DISPLAY INVISIBLE (7725 4250);
FORCEPROP 1 LAST BODY_TYPE PLUMBING
J 2
(7725 4300);
DISPLAY 0.872340 (7725 4300);
PAINT GREEN (7725 4300);
DISPLAY INVISIBLE (7725 4300);
FORCEPROP 1 LAST HDL_TAP TRUE
J 2
(7400 4125);
DISPLAY 0.872340 (7400 4125);
PAINT GREEN (7400 4125);
DISPLAY INVISIBLE (7400 4125);
FORCEPROP 1 LAST PATH I150
J 2
(7727 4250);
DISPLAY 0.872340 (7727 4250);
PAINT GREEN (7727 4250);
DISPLAY INVISIBLE (7727 4250);
FORCEADD TAP..1
R 2
(7575 4300);
FORCEPROP 3 LASTPIN (7625 4300) SIG_NAME P3E_PCH_M2_TX_C_DN<0>
J 0
(7635 4310);
DISPLAY 0.659574 (7635 4310);
PAINT MONO (7635 4310);
DISPLAY INVISIBLE (7635 4310);
FORCEPROP 1 LASTPIN (7625 4300) BN 0
J 2
(7637 4308);
DISPLAY 0.680851 (7637 4308);
PAINT GREEN (7637 4308);
FORCEPROP 2 LAST CDS_LIB standard
J 0
(7575 4300);
DISPLAY INVISIBLE (7575 4300);
FORCEPROP 1 LAST BODY_TYPE PLUMBING
J 2
(7575 4350);
DISPLAY 0.872340 (7575 4350);
PAINT GREEN (7575 4350);
DISPLAY INVISIBLE (7575 4350);
FORCEPROP 1 LAST HDL_TAP TRUE
J 2
(7250 4175);
DISPLAY 0.872340 (7250 4175);
PAINT GREEN (7250 4175);
DISPLAY INVISIBLE (7250 4175);
FORCEPROP 1 LAST PATH I151
J 2
(7577 4300);
DISPLAY 0.872340 (7577 4300);
PAINT GREEN (7577 4300);
DISPLAY INVISIBLE (7577 4300);
FORCEADD OFFPAGE..1
(6125 4525);
FORCEPROP 2 LAST $XR0 181 
J 0
(5843 4525);
DISPLAY 0.638298 (5843 4525);
PAINT MONO (5843 4525);
FORCEPROP 2 LAST CDS_LIB standard
J 0
(6125 4525);
PAINT MONO (6125 4525);
DISPLAY INVISIBLE (6125 4525);
FORCEPROP 1 LAST OFFPAGE TRUE
J 0
(6450 4400);
DISPLAY 0.872340 (6450 4400);
PAINT GREEN (6450 4400);
DISPLAY INVISIBLE (6450 4400);
FORCEPROP 1 LAST COMMENT_BODY TRUE
J 0
(6250 4425);
DISPLAY 0.872340 (6250 4425);
PAINT GREEN (6250 4425);
DISPLAY INVISIBLE (6250 4425);
FORCEPROP 2 LAST PATH I154
J 0
(5850 4575);
DISPLAY 1.021277 (5850 4575);
DISPLAY INVISIBLE (5850 4575);
FORCEADD OFFPAGE..1
(6125 4575);
FORCEPROP 2 LAST $XR0 181 
J 0
(5843 4575);
DISPLAY 0.638298 (5843 4575);
PAINT MONO (5843 4575);
FORCEPROP 2 LAST CDS_LIB standard
J 0
(6125 4575);
PAINT MONO (6125 4575);
DISPLAY INVISIBLE (6125 4575);
FORCEPROP 1 LAST OFFPAGE TRUE
J 0
(6450 4450);
DISPLAY 0.872340 (6450 4450);
PAINT GREEN (6450 4450);
DISPLAY INVISIBLE (6450 4450);
FORCEPROP 1 LAST COMMENT_BODY TRUE
J 0
(6250 4475);
DISPLAY 0.872340 (6250 4475);
PAINT GREEN (6250 4475);
DISPLAY INVISIBLE (6250 4475);
FORCEPROP 2 LAST PATH I155
J 0
(5850 4625);
DISPLAY 1.021277 (5850 4625);
DISPLAY INVISIBLE (5850 4625);
FORCEADD OFFPAGE..1
(6875 3200);
FORCEPROP 2 LAST $XR0 179 
J 0
(6623 3200);
DISPLAY 0.638298 (6623 3200);
PAINT MONO (6623 3200);
FORCEPROP 2 LAST CDS_LIB standard
J 0
(6875 3200);
PAINT MONO (6875 3200);
DISPLAY INVISIBLE (6875 3200);
FORCEPROP 1 LAST OFFPAGE TRUE
J 0
(7200 3075);
DISPLAY 0.872340 (7200 3075);
DISPLAY INVISIBLE (7200 3075);
FORCEPROP 1 LAST COMMENT_BODY TRUE
J 0
(7000 3100);
DISPLAY 0.872340 (7000 3100);
PAINT GREEN (7000 3100);
DISPLAY INVISIBLE (7000 3100);
FORCEPROP 2 LAST PATH I158
J 0
(6600 3250);
DISPLAY 1.021277 (6600 3250);
DISPLAY INVISIBLE (6600 3250);
FORCEADD OFFPAGE..1
(6875 3150);
FORCEPROP 2 LAST $XR0 179 
J 0
(6623 3150);
DISPLAY 0.638298 (6623 3150);
PAINT MONO (6623 3150);
FORCEPROP 2 LAST CDS_LIB standard
J 0
(6875 3150);
PAINT MONO (6875 3150);
DISPLAY INVISIBLE (6875 3150);
FORCEPROP 1 LAST OFFPAGE TRUE
J 0
(7200 3025);
DISPLAY 0.872340 (7200 3025);
DISPLAY INVISIBLE (7200 3025);
FORCEPROP 1 LAST COMMENT_BODY TRUE
J 0
(7000 3050);
DISPLAY 0.872340 (7000 3050);
PAINT GREEN (7000 3050);
DISPLAY INVISIBLE (7000 3050);
FORCEPROP 2 LAST PATH I159
J 0
(6600 3200);
DISPLAY 1.021277 (6600 3200);
DISPLAY INVISIBLE (6600 3200);
FORCEADD OFFPAGE..5
(6125 4425);
FORCEPROP 2 LAST $XR0 181 
J 0
(5870 4425);
DISPLAY 0.638298 (5870 4425);
PAINT MONO (5870 4425);
FORCEPROP 2 LAST CDS_LIB standard
J 0
(6125 4425);
PAINT MONO (6125 4425);
DISPLAY INVISIBLE (6125 4425);
FORCEPROP 2 LAST PATH I160
J 0
(5850 4475);
DISPLAY 1.021277 (5850 4475);
DISPLAY INVISIBLE (5850 4475);
FORCEPROP 1 LAST OFFPAGE TRUE
J 0
(6450 4300);
DISPLAY 0.872340 (6450 4300);
DISPLAY INVISIBLE (6450 4300);
FORCEPROP 1 LAST COMMENT_BODY TRUE
J 0
(6225 4350);
DISPLAY 0.872340 (6225 4350);
PAINT GREEN (6225 4350);
DISPLAY INVISIBLE (6225 4350);
FORCEADD OFFPAGE..5
(6125 4475);
FORCEPROP 2 LAST $XR0 181 
J 0
(5870 4475);
DISPLAY 0.638298 (5870 4475);
PAINT MONO (5870 4475);
FORCEPROP 2 LAST CDS_LIB standard
J 0
(6125 4475);
PAINT MONO (6125 4475);
DISPLAY INVISIBLE (6125 4475);
FORCEPROP 2 LAST PATH I161
J 0
(5850 4525);
DISPLAY 1.021277 (5850 4525);
DISPLAY INVISIBLE (5850 4525);
FORCEPROP 1 LAST COMMENT_BODY TRUE
J 0
(6225 4400);
DISPLAY 0.872340 (6225 4400);
PAINT GREEN (6225 4400);
DISPLAY INVISIBLE (6225 4400);
FORCEPROP 1 LAST OFFPAGE TRUE
J 0
(6450 4350);
DISPLAY 0.872340 (6450 4350);
DISPLAY INVISIBLE (6450 4350);
FORCEADD Q_RES..1
(6425 3350);
FORCEPROP 1 LAST PART_NUMBER CS00002JB13
J 0
(6300 3425);
DISPLAY 0.638298 (6300 3425);
DISPLAY INVISIBLE (6300 3425);
FORCEPROP 1 LAST VALUE 0
J 2
(6600 3350);
DISPLAY 0.638298 (6600 3350);
FORCEPROP 1 LAST TOLERANCE 5%
J 0
(6625 3350);
DISPLAY 0.638298 (6625 3350);
FORCEPROP 1 LAST MATERIAL CHIP
J 0
(6700 3350);
DISPLAY 0.638298 (6700 3350);
FORCEPROP 1 LAST $LOCATION R486
J 0
(6200 3350);
DISPLAY 0.787234 (6200 3350);
FORCEPROP 1 LASTPIN (6325 3350) $PN 1
J 0
(6337 3362);
DISPLAY 0.787234 (6337 3362);
FORCEPROP 1 LASTPIN (6525 3350) $PN 2
J 0
(6487 3362);
DISPLAY 0.787234 (6487 3362);
FORCEPROP 2 LAST CDS_LIB pure_quanta
J 0
(6425 3350);
PAINT MONO (6425 3350);
DISPLAY INVISIBLE (6425 3350);
FORCEPROP 1 LAST PATH I162
J 0
(6375 3500);
DISPLAY 0.978723 (6375 3500);
PAINT WHITE (6375 3500);
DISPLAY INVISIBLE (6375 3500);
FORCEPROP 1 LAST WATTAGE 1/16W
J 2
(6600 3475);
DISPLAY 0.638298 (6600 3475);
DISPLAY INVISIBLE (6600 3475);
FORCEPROP 1 LAST PACK_TYPE 0402LF
J 0
(6700 3350);
DISPLAY 0.638298 (6700 3350);
DISPLAY INVISIBLE (6700 3350);
FORCEPROP 2 LAST CDS_LOCATION R486
J 0
(6375 3550);
DISPLAY 1.021277 (6375 3550);
DISPLAY INVISIBLE (6375 3550);
FORCEPROP 2 LAST $SEC 1
J 0
(6375 3550);
DISPLAY 0.680851 (6375 3550);
PAINT MONO (6375 3550);
DISPLAY INVISIBLE (6375 3550);
FORCEPROP 2 LAST CDS_SEC 1
J 0
(6375 3550);
DISPLAY 1.021277 (6375 3550);
DISPLAY INVISIBLE (6375 3550);
FORCEADD OFFPAGE..5
(5325 3350);
FORCEPROP 2 LAST $XR1 190 
J 0
(4920 3350);
DISPLAY 0.638298 (4920 3350);
PAINT MONO (4920 3350);
FORCEPROP 2 LAST $XR0 183 
J 0
(5040 3350);
DISPLAY 0.638298 (5040 3350);
PAINT MONO (5040 3350);
FORCEPROP 2 LAST CDS_LIB standard
J 0
(5325 3350);
PAINT MONO (5325 3350);
DISPLAY INVISIBLE (5325 3350);
FORCEPROP 2 LAST PATH I163
J 0
(5050 3400);
DISPLAY 1.021277 (5050 3400);
DISPLAY INVISIBLE (5050 3400);
FORCEPROP 1 LAST COMMENT_BODY TRUE
J 0
(5425 3275);
DISPLAY 0.872340 (5425 3275);
PAINT GREEN (5425 3275);
DISPLAY INVISIBLE (5425 3275);
FORCEPROP 1 LAST OFFPAGE TRUE
J 0
(5650 3225);
DISPLAY 0.872340 (5650 3225);
DISPLAY INVISIBLE (5650 3225);
FORCEADD Q_RES..2
(5450 3075);
FORCEPROP 1 LAST PART_NUMBER CS24702FB06
J 0
(5490 2950);
DISPLAY 0.638298 (5490 2950);
DISPLAY INVISIBLE (5490 2950);
FORCEPROP 1 LAST PACK_TYPE 0402LF
J 0
(5490 2900);
DISPLAY 0.638298 (5490 2900);
FORCEPROP 1 LAST VALUE 4.7K
J 0
(5495 3150);
DISPLAY 0.638298 (5495 3150);
FORCEPROP 1 LAST TOLERANCE 1%
J 0
(5495 3100);
DISPLAY 0.638298 (5495 3100);
FORCEPROP 1 LAST MATERIAL EMPTY
J 0
(5490 3000);
DISPLAY 0.638298 (5490 3000);
PAINT RED (5490 3000);
FORCEPROP 1 LAST WATTAGE 1/16W
J 0
(5490 3050);
DISPLAY 0.638298 (5490 3050);
FORCEPROP 1 LAST $LOCATION R491
J 0
(5495 3200);
DISPLAY 0.978723 (5495 3200);
FORCEPROP 1 LASTPIN (5450 3175) $PN 1
J 0
(5455 3137);
DISPLAY 0.787234 (5455 3137);
FORCEPROP 1 LASTPIN (5450 2975) $PN 2
J 0
(5455 2985);
DISPLAY 0.787234 (5455 2985);
FORCEPROP 2 LAST CDS_LIB pure_quanta
J 0
(5450 3075);
PAINT MONO (5450 3075);
DISPLAY INVISIBLE (5450 3075);
FORCEPROP 1 LAST PATH I164
J 0
(5500 3250);
DISPLAY 0.978723 (5500 3250);
PAINT WHITE (5500 3250);
DISPLAY INVISIBLE (5500 3250);
FORCEPROP 2 LAST CDS_LOCATION R491
J 0
(5500 3300);
DISPLAY 1.021277 (5500 3300);
DISPLAY INVISIBLE (5500 3300);
FORCEPROP 2 LAST $SEC 1
J 0
(5500 3300);
DISPLAY 0.680851 (5500 3300);
PAINT MONO (5500 3300);
DISPLAY INVISIBLE (5500 3300);
FORCEPROP 2 LAST CDS_SEC 1
J 0
(5500 3300);
DISPLAY 1.021277 (5500 3300);
DISPLAY INVISIBLE (5500 3300);
FORCEADD UNIVERSAL_GND..1
(5450 2850);
FORCEPROP 3 LASTPIN (5450 2900) SIG_NAME GND\g
J 0
(5460 2910);
DISPLAY 0.659574 (5460 2910);
PAINT MONO (5460 2910);
DISPLAY INVISIBLE (5460 2910);
FORCEPROP 2 LAST CDS_LIB logical_power
J 0
(5450 2850);
PAINT MONO (5450 2850);
DISPLAY INVISIBLE (5450 2850);
FORCEPROP 1 LAST PATH I165
J 0
(5525 2850);
DISPLAY 0.872340 (5525 2850);
PAINT AQUA (5525 2850);
DISPLAY INVISIBLE (5525 2850);
FORCEPROP 1 LAST HDL_POWER GND
J 1
(5475 2775);
DISPLAY 0.872340 (5475 2775);
PAINT GREEN (5475 2775);
DISPLAY INVISIBLE (5475 2775);
FORCEADD Q_RES..1
(10600 3275);
FORCEPROP 1 LAST PART_NUMBER CS31002FB08
J 0
(10450 3350);
DISPLAY 0.404255 (10450 3350);
DISPLAY INVISIBLE (10450 3350);
FORCEPROP 1 LAST WATTAGE 1/16W
J 2
(10750 3375);
DISPLAY 0.404255 (10750 3375);
FORCEPROP 1 LAST MATERIAL CHIP
J 0
(10900 3275);
DISPLAY 0.638298 (10900 3275);
FORCEPROP 1 LAST TOLERANCE 1%
J 0
(10825 3275);
DISPLAY 0.638298 (10825 3275);
FORCEPROP 1 LAST VALUE 10K
J 2
(10800 3275);
DISPLAY 0.638298 (10800 3275);
FORCEPROP 1 LAST PACK_TYPE 0402LF
J 0
(10450 3375);
DISPLAY 0.404255 (10450 3375);
FORCEPROP 1 LAST $LOCATION R1396
J 0
(10375 3275);
DISPLAY 0.638298 (10375 3275);
FORCEPROP 1 LASTPIN (10500 3275) $PN 1
J 0
(10512 3287);
DISPLAY 0.787234 (10512 3287);
FORCEPROP 1 LASTPIN (10700 3275) $PN 2
J 0
(10662 3287);
DISPLAY 0.787234 (10662 3287);
FORCEPROP 2 LAST CDS_LIB pure_quanta
J 0
(10600 3275);
PAINT MONO (10600 3275);
DISPLAY INVISIBLE (10600 3275);
FORCEPROP 1 LAST PATH I167
J 0
(10550 3425);
DISPLAY 0.978723 (10550 3425);
PAINT WHITE (10550 3425);
DISPLAY INVISIBLE (10550 3425);
FORCEPROP 2 LAST CDS_LOCATION R1396
J 0
(10550 3475);
DISPLAY 1.021277 (10550 3475);
DISPLAY INVISIBLE (10550 3475);
FORCEPROP 2 LAST $SEC 1
J 0
(10550 3475);
DISPLAY 0.680851 (10550 3475);
PAINT MONO (10550 3475);
DISPLAY INVISIBLE (10550 3475);
FORCEPROP 2 LAST CDS_SEC 1
J 0
(10550 3475);
DISPLAY 1.021277 (10550 3475);
DISPLAY INVISIBLE (10550 3475);
FORCEADD UNIVERSAL_GND..1
(7975 2100);
FORCEPROP 3 LASTPIN (7975 2150) SIG_NAME GND\g
J 0
(7985 2160);
DISPLAY 0.659574 (7985 2160);
PAINT MONO (7985 2160);
DISPLAY INVISIBLE (7985 2160);
FORCEPROP 1 LAST HDL_POWER GND
J 1
(8000 2025);
DISPLAY 0.872340 (8000 2025);
PAINT GREEN (8000 2025);
DISPLAY INVISIBLE (8000 2025);
FORCEPROP 1 LAST PATH I172
J 0
(8050 2100);
DISPLAY 0.872340 (8050 2100);
PAINT AQUA (8050 2100);
DISPLAY INVISIBLE (8050 2100);
FORCEPROP 2 LAST CDS_LIB logical_power
J 0
(7975 2100);
PAINT MONO (7975 2100);
DISPLAY INVISIBLE (7975 2100);
FORCEADD Q_RES..2
R 2
(6975 3925);
FORCEPROP 1 LAST PART_NUMBER CS21002FB06
J 2
(6935 3800);
DISPLAY 0.510638 (6935 3800);
DISPLAY INVISIBLE (6935 3800);
FORCEPROP 1 LAST PACK_TYPE 0402LF
J 2
(6935 3750);
DISPLAY 0.510638 (6935 3750);
FORCEPROP 1 LAST MATERIAL CHIP
J 2
(6935 3850);
DISPLAY 0.510638 (6935 3850);
FORCEPROP 1 LAST TOLERANCE 1%
J 2
(6930 3950);
DISPLAY 0.510638 (6930 3950);
FORCEPROP 1 LAST WATTAGE 1/16W
J 2
(6935 3900);
DISPLAY 0.510638 (6935 3900);
FORCEPROP 1 LAST VALUE 1K
J 2
(6930 4000);
DISPLAY 0.510638 (6930 4000);
FORCEPROP 1 LAST $LOCATION R487
J 2
(6930 4050);
DISPLAY 0.638298 (6930 4050);
FORCEPROP 1 LASTPIN (6975 4025) $PN 1
J 2
(6970 3987);
DISPLAY 0.787234 (6970 3987);
FORCEPROP 1 LASTPIN (6975 3825) $PN 2
J 2
(6970 3835);
DISPLAY 0.787234 (6970 3835);
FORCEPROP 1 LAST PATH I173
J 2
(6925 4100);
DISPLAY 0.978723 (6925 4100);
PAINT WHITE (6925 4100);
DISPLAY INVISIBLE (6925 4100);
FORCEPROP 2 LAST CDS_LIB pure_quanta
J 2
(6975 3925);
PAINT MONO (6975 3925);
DISPLAY INVISIBLE (6975 3925);
FORCEPROP 2 LAST CDS_LOCATION R487
J 2
(6925 4150);
DISPLAY 1.021277 (6925 4150);
DISPLAY INVISIBLE (6925 4150);
FORCEPROP 2 LAST $SEC 1
J 2
(6925 4150);
DISPLAY 0.680851 (6925 4150);
PAINT MONO (6925 4150);
DISPLAY INVISIBLE (6925 4150);
FORCEPROP 2 LAST CDS_SEC 1
J 2
(6925 4150);
DISPLAY 1.021277 (6925 4150);
DISPLAY INVISIBLE (6925 4150);
FORCEADD UNIVERSAL_POWER..1
(6975 4150);
FORCEPROP 3 LASTPIN (6975 4100) SIG_NAME P3V3_AUX\g
J 0
(6985 4110);
DISPLAY 0.659574 (6985 4110);
PAINT MONO (6985 4110);
DISPLAY INVISIBLE (6985 4110);
FORCEPROP 1 LAST HDL_POWER P3V3_AUX
J 1
(6975 4200);
DISPLAY 0.872340 (6975 4200);
PAINT GREEN (6975 4200);
FORCEPROP 2 LAST CDS_LIB logical_power
J 0
(6975 4150);
PAINT MONO (6975 4150);
DISPLAY INVISIBLE (6975 4150);
FORCEPROP 1 LAST PATH I174
J 0
(7025 4175);
DISPLAY 0.872340 (7025 4175);
PAINT AQUA (7025 4175);
DISPLAY INVISIBLE (7025 4175);
FORCEADD OFFPAGE..5
(6875 2400);
FORCEPROP 2 LAST $XR0 215 
J 0
(6590 2400);
DISPLAY 0.638298 (6590 2400);
PAINT MONO (6590 2400);
FORCEPROP 1 LAST COMMENT_BODY TRUE
J 0
(6975 2325);
DISPLAY 0.872340 (6975 2325);
PAINT GREEN (6975 2325);
DISPLAY INVISIBLE (6975 2325);
FORCEPROP 1 LAST OFFPAGE TRUE
J 0
(7200 2275);
DISPLAY 0.872340 (7200 2275);
DISPLAY INVISIBLE (7200 2275);
FORCEPROP 2 LAST CDS_LIB standard
J 0
(6875 2400);
PAINT MONO (6875 2400);
DISPLAY INVISIBLE (6875 2400);
FORCEPROP 2 LAST PATH I175
J 0
(6600 2450);
DISPLAY 1.021277 (6600 2450);
DISPLAY INVISIBLE (6600 2450);
FORCEADD Q_RES..2
(6975 2700);
FORCEPROP 1 LAST PART_NUMBER CS24702FB06
J 0
(7015 2575);
DISPLAY 0.638298 (7015 2575);
DISPLAY INVISIBLE (7015 2575);
FORCEPROP 1 LAST PACK_TYPE 0402LF
J 0
(7015 2525);
DISPLAY 0.638298 (7015 2525);
FORCEPROP 1 LAST MATERIAL CHIP
J 0
(7015 2625);
DISPLAY 0.638298 (7015 2625);
FORCEPROP 1 LAST WATTAGE 1/16W
J 0
(7015 2675);
DISPLAY 0.638298 (7015 2675);
FORCEPROP 1 LAST VALUE 4.7K
J 0
(7020 2775);
DISPLAY 0.638298 (7020 2775);
FORCEPROP 1 LAST TOLERANCE 1%
J 0
(7020 2725);
DISPLAY 0.787234 (7020 2725);
FORCEPROP 1 LAST $LOCATION R478
J 0
(7020 2825);
DISPLAY 0.787234 (7020 2825);
FORCEPROP 1 LASTPIN (6975 2800) $PN 1
J 0
(6980 2762);
DISPLAY 0.787234 (6980 2762);
FORCEPROP 1 LASTPIN (6975 2600) $PN 2
J 0
(6980 2610);
DISPLAY 0.787234 (6980 2610);
FORCEPROP 2 LAST CDS_LIB pure_quanta
J 0
(6975 2700);
PAINT MONO (6975 2700);
DISPLAY INVISIBLE (6975 2700);
FORCEPROP 1 LAST PATH I176
J 0
(7025 2875);
DISPLAY 0.978723 (7025 2875);
PAINT WHITE (7025 2875);
DISPLAY INVISIBLE (7025 2875);
FORCEPROP 2 LAST CDS_LOCATION R478
J 0
(7025 2925);
DISPLAY 1.021277 (7025 2925);
DISPLAY INVISIBLE (7025 2925);
FORCEPROP 2 LAST $SEC 1
J 0
(7025 2925);
DISPLAY 0.680851 (7025 2925);
PAINT MONO (7025 2925);
DISPLAY INVISIBLE (7025 2925);
FORCEPROP 2 LAST CDS_SEC 1
J 0
(7025 2925);
DISPLAY 1.021277 (7025 2925);
DISPLAY INVISIBLE (7025 2925);
FORCEADD UNIVERSAL_POWER..1
(6975 2925);
FORCEPROP 3 LASTPIN (6975 2875) SIG_NAME P3V3_AUX\g
J 0
(6985 2885);
DISPLAY 0.659574 (6985 2885);
PAINT MONO (6985 2885);
DISPLAY INVISIBLE (6985 2885);
FORCEPROP 1 LAST HDL_POWER P3V3_AUX
J 1
(6975 2975);
DISPLAY 0.872340 (6975 2975);
PAINT GREEN (6975 2975);
FORCEPROP 2 LAST CDS_LIB logical_power
J 0
(6975 2925);
PAINT MONO (6975 2925);
DISPLAY INVISIBLE (6975 2925);
FORCEPROP 1 LAST PATH I177
J 0
(7025 2950);
DISPLAY 0.872340 (7025 2950);
PAINT AQUA (7025 2950);
DISPLAY INVISIBLE (7025 2950);
FORCEADD SCONN75K_APCI0155P004A..1
R 2
(8725 3325);
FORCEPROP 1 LAST PART_NUMBER DFHS75FR313
J 2
(9174 4554);
DISPLAY 0.723404 (9174 4554);
PAINT GREEN (9174 4554);
DISPLAY INVISIBLE (9174 4554);
FORCEPROP 2 LAST VALUE SCONN75K_APCI0155-P004A
J 2
(9025 4750);
DISPLAY 0.638298 (9025 4750);
FORCEPROP 2 LAST PART_TYPE SMLF
J 2
(8450 4800);
DISPLAY 0.638298 (8450 4800);
FORCEPROP 1 LAST MATERIAL EMPTY
J 2
(9174 4465);
DISPLAY 0.723404 (9174 4465);
PAINT GREEN (9174 4465);
FORCEPROP 1 LAST $LOCATION J59
J 2
(9174 4638);
DISPLAY 0.723404 (9174 4638);
PAINT GREEN (9174 4638);
FORCEPROP 2 LASTPIN (9325 4000) $PN 2
J 0
(9335 4010);
DISPLAY 0.808511 (9335 4010);
FORCEPROP 2 LASTPIN (9325 4050) $PN 4
J 0
(9335 4060);
DISPLAY 0.808511 (9335 4060);
FORCEPROP 2 LASTPIN (9325 4100) $PN 12
J 0
(9335 4110);
DISPLAY 0.808511 (9335 4110);
FORCEPROP 2 LASTPIN (9325 4150) $PN 14
J 0
(9335 4160);
DISPLAY 0.808511 (9335 4160);
FORCEPROP 2 LASTPIN (9325 4200) $PN 16
J 0
(9335 4210);
DISPLAY 0.808511 (9335 4210);
FORCEPROP 2 LASTPIN (9325 4250) $PN 18
J 0
(9335 4260);
DISPLAY 0.808511 (9335 4260);
FORCEPROP 2 LASTPIN (9325 4300) $PN 70
J 0
(9335 4310);
DISPLAY 0.808511 (9335 4310);
FORCEPROP 2 LASTPIN (9325 4350) $PN 72
J 0
(9335 4360);
DISPLAY 0.808511 (9335 4360);
FORCEPROP 2 LASTPIN (9325 4400) $PN 74
J 0
(9335 4410);
DISPLAY 0.808511 (9335 4410);
FORCEPROP 2 LASTPIN (8125 3350) $PN 52
J 2
(8115 3360);
DISPLAY 0.808511 (8115 3360);
FORCEPROP 2 LASTPIN (9325 3600) $PN 10
J 0
(9335 3610);
DISPLAY 0.808511 (9335 3610);
FORCEPROP 2 LASTPIN (8125 3550) $PN 38
J 2
(8115 3560);
DISPLAY 0.808511 (8115 3560);
FORCEPROP 2 LASTPIN (8125 2300) $PN G1
J 2
(8115 2310);
DISPLAY 0.808511 (8115 2310);
FORCEPROP 2 LASTPIN (8125 2250) $PN G2
J 2
(8115 2260);
DISPLAY 0.808511 (8115 2260);
FORCEPROP 2 LASTPIN (8125 2400) $PN 1
J 2
(8115 2410);
DISPLAY 0.808511 (8115 2410);
FORCEPROP 2 LASTPIN (8125 2450) $PN 3
J 2
(8115 2460);
DISPLAY 0.808511 (8115 2460);
FORCEPROP 2 LASTPIN (8125 2500) $PN 9
J 2
(8115 2510);
DISPLAY 0.808511 (8115 2510);
FORCEPROP 2 LASTPIN (8125 2550) $PN 15
J 2
(8115 2560);
DISPLAY 0.808511 (8115 2560);
FORCEPROP 2 LASTPIN (8125 2600) $PN 21
J 2
(8115 2610);
DISPLAY 0.808511 (8115 2610);
FORCEPROP 2 LASTPIN (8125 2650) $PN 27
J 2
(8115 2660);
DISPLAY 0.808511 (8115 2660);
FORCEPROP 2 LASTPIN (8125 2700) $PN 33
J 2
(8115 2710);
DISPLAY 0.808511 (8115 2710);
FORCEPROP 2 LASTPIN (8125 2750) $PN 39
J 2
(8115 2760);
DISPLAY 0.808511 (8115 2760);
FORCEPROP 2 LASTPIN (8125 2800) $PN 45
J 2
(8115 2810);
DISPLAY 0.808511 (8115 2810);
FORCEPROP 2 LASTPIN (8125 2850) $PN 51
J 2
(8115 2860);
DISPLAY 0.808511 (8115 2860);
FORCEPROP 2 LASTPIN (8125 2900) $PN 57
J 2
(8115 2910);
DISPLAY 0.808511 (8115 2910);
FORCEPROP 2 LASTPIN (8125 2950) $PN 71
J 2
(8115 2960);
DISPLAY 0.808511 (8115 2960);
FORCEPROP 2 LASTPIN (8125 3000) $PN 73
J 2
(8115 3010);
DISPLAY 0.808511 (8115 3010);
FORCEPROP 2 LASTPIN (8125 3050) $PN 75
J 2
(8115 3060);
DISPLAY 0.808511 (8115 3060);
FORCEPROP 2 LASTPIN (9325 2450) $PN 6
J 0
(9335 2460);
DISPLAY 0.808511 (9335 2460);
FORCEPROP 2 LASTPIN (9325 2500) $PN 8
J 0
(9335 2510);
DISPLAY 0.808511 (9335 2510);
FORCEPROP 2 LASTPIN (9325 2550) $PN 20
J 0
(9335 2560);
DISPLAY 0.808511 (9335 2560);
FORCEPROP 2 LASTPIN (9325 2600) $PN 22
J 0
(9335 2610);
DISPLAY 0.808511 (9335 2610);
FORCEPROP 2 LASTPIN (9325 2650) $PN 24
J 0
(9335 2660);
DISPLAY 0.808511 (9335 2660);
FORCEPROP 2 LASTPIN (9325 2700) $PN 26
J 0
(9335 2710);
DISPLAY 0.808511 (9335 2710);
FORCEPROP 2 LASTPIN (9325 2750) $PN 28
J 0
(9335 2760);
DISPLAY 0.808511 (9335 2760);
FORCEPROP 2 LASTPIN (9325 2800) $PN 30
J 0
(9335 2810);
DISPLAY 0.808511 (9335 2810);
FORCEPROP 2 LASTPIN (9325 2850) $PN 32
J 0
(9335 2860);
DISPLAY 0.808511 (9335 2860);
FORCEPROP 2 LASTPIN (9325 2900) $PN 34
J 0
(9335 2910);
DISPLAY 0.808511 (9335 2910);
FORCEPROP 2 LASTPIN (9325 2950) $PN 36
J 0
(9335 2960);
DISPLAY 0.808511 (9335 2960);
FORCEPROP 2 LASTPIN (9325 3000) $PN 40
J 0
(9335 3010);
DISPLAY 0.808511 (9335 3010);
FORCEPROP 2 LASTPIN (9325 3050) $PN 42
J 0
(9335 3060);
DISPLAY 0.808511 (9335 3060);
FORCEPROP 2 LASTPIN (9325 3100) $PN 44
J 0
(9335 3110);
DISPLAY 0.808511 (9335 3110);
FORCEPROP 2 LASTPIN (9325 3150) $PN 46
J 0
(9335 3160);
DISPLAY 0.808511 (9335 3160);
FORCEPROP 2 LASTPIN (9325 3200) $PN 48
J 0
(9335 3210);
DISPLAY 0.808511 (9335 3210);
FORCEPROP 2 LASTPIN (9325 3250) $PN 56
J 0
(9335 3260);
DISPLAY 0.808511 (9335 3260);
FORCEPROP 2 LASTPIN (9325 3300) $PN 58
J 0
(9335 3310);
DISPLAY 0.808511 (9335 3310);
FORCEPROP 2 LASTPIN (9325 3350) $PN 67
J 0
(9335 3360);
DISPLAY 0.808511 (9335 3360);
FORCEPROP 2 LASTPIN (9325 3500) $PN 69
J 0
(9335 3510);
DISPLAY 0.808511 (9335 3510);
FORCEPROP 2 LASTPIN (9325 3850) $PN 41
J 0
(9335 3860);
DISPLAY 0.808511 (9335 3860);
FORCEPROP 2 LASTPIN (8125 3850) $PN 29
J 2
(8115 3860);
DISPLAY 0.808511 (8115 3860);
FORCEPROP 2 LASTPIN (8125 4100) $PN 17
J 2
(8115 4110);
DISPLAY 0.808511 (8115 4110);
FORCEPROP 2 LASTPIN (8125 4350) $PN 5
J 2
(8115 4360);
DISPLAY 0.808511 (8115 4360);
FORCEPROP 2 LASTPIN (9325 3900) $PN 43
J 0
(9335 3910);
DISPLAY 0.808511 (9335 3910);
FORCEPROP 2 LASTPIN (8125 3900) $PN 31
J 2
(8115 3910);
DISPLAY 0.808511 (8115 3910);
FORCEPROP 2 LASTPIN (8125 4150) $PN 19
J 2
(8115 4160);
DISPLAY 0.808511 (8115 4160);
FORCEPROP 2 LASTPIN (8125 4400) $PN 7
J 2
(8115 4410);
DISPLAY 0.808511 (8115 4410);
FORCEPROP 2 LASTPIN (8125 3450) $PN 50
J 2
(8115 3460);
DISPLAY 0.808511 (8115 3460);
FORCEPROP 2 LASTPIN (9325 3700) $PN 47
J 0
(9335 3710);
DISPLAY 0.808511 (9335 3710);
FORCEPROP 2 LASTPIN (8125 3750) $PN 35
J 2
(8115 3760);
DISPLAY 0.808511 (8115 3760);
FORCEPROP 2 LASTPIN (8125 4000) $PN 23
J 2
(8115 4010);
DISPLAY 0.808511 (8115 4010);
FORCEPROP 2 LASTPIN (8125 4250) $PN 11
J 2
(8115 4260);
DISPLAY 0.808511 (8115 4260);
FORCEPROP 2 LASTPIN (9325 3750) $PN 49
J 0
(9335 3760);
DISPLAY 0.808511 (9335 3760);
FORCEPROP 2 LASTPIN (8125 3800) $PN 37
J 2
(8115 3810);
DISPLAY 0.808511 (8115 3810);
FORCEPROP 2 LASTPIN (8125 4050) $PN 25
J 2
(8115 4060);
DISPLAY 0.808511 (8115 4060);
FORCEPROP 2 LASTPIN (8125 4300) $PN 13
J 2
(8115 4310);
DISPLAY 0.808511 (8115 4310);
FORCEPROP 2 LASTPIN (8125 3300) $PN 54
J 2
(8115 3310);
DISPLAY 0.808511 (8115 3310);
FORCEPROP 2 LASTPIN (8125 3150) $PN 53
J 2
(8115 3160);
DISPLAY 0.808511 (8115 3160);
FORCEPROP 2 LASTPIN (8125 3200) $PN 55
J 2
(8115 3210);
DISPLAY 0.808511 (8115 3210);
FORCEPROP 2 LASTPIN (8125 3650) $PN 68
J 2
(8115 3660);
DISPLAY 0.808511 (8115 3660);
FORCEPROP 1 LAST PIN_NAMES_ROTATE True
J 2
(8725 3325);
DISPLAY 0.489362 (8725 3325);
PAINT GREEN (8725 3325);
DISPLAY INVISIBLE (8725 3325);
FORCEPROP 1 LAST CDS_LMAN_SYM_OUTLINE -450,1125,450,-1125
J 2
(8725 3325);
DISPLAY 0.468085 (8725 3325);
PAINT GREEN (8725 3325);
DISPLAY INVISIBLE (8725 3325);
FORCEPROP 2 LAST CDS_LIB pure_quanta
J 0
(8725 3325);
PAINT MONO (8725 3325);
DISPLAY INVISIBLE (8725 3325);
FORCEPROP 1 LAST PATH I178
J 2
(8275 2200);
DISPLAY 0.723404 (8275 2200);
PAINT GREEN (8275 2200);
DISPLAY INVISIBLE (8275 2200);
FORCEPROP 2 LAST CDS_LOCATION J59
J 0
(8550 4725);
DISPLAY 1.021277 (8550 4725);
DISPLAY INVISIBLE (8550 4725);
FORCEPROP 2 LAST $SEC 1
J 0
(8450 4850);
DISPLAY 0.680851 (8450 4850);
PAINT MONO (8450 4850);
DISPLAY INVISIBLE (8450 4850);
FORCEPROP 2 LAST CDS_SEC 1
J 0
(8550 4725);
DISPLAY 1.021277 (8550 4725);
DISPLAY INVISIBLE (8550 4725);
FORCEADD OFFPAGE..4
(10625 3000);
FORCEPROP 2 LAST $XR0 194 
J 0
(10841 3000);
DISPLAY 0.638298 (10841 3000);
PAINT MONO (10841 3000);
FORCEPROP 1 LAST OFFPAGE TRUE
J 0
(10950 2875);
DISPLAY 0.872340 (10950 2875);
DISPLAY INVISIBLE (10950 2875);
FORCEPROP 1 LAST COMMENT_BODY TRUE
J 0
(10600 2900);
DISPLAY 0.872340 (10600 2900);
PAINT GREEN (10600 2900);
DISPLAY INVISIBLE (10600 2900);
FORCEPROP 2 LAST PATH I231
J 0
(10825 3050);
DISPLAY 1.021277 (10825 3050);
DISPLAY INVISIBLE (10825 3050);
FORCEPROP 2 LAST CDS_LIB standard
J 0
(10625 3000);
DISPLAY INVISIBLE (10625 3000);
FORCEADD TAP..1
R 2
(7400 4400);
FORCEPROP 3 LASTPIN (7450 4400) SIG_NAME P3E_PCH_M2_RX_DP<0>
J 0
(7460 4410);
DISPLAY 0.659574 (7460 4410);
PAINT MONO (7460 4410);
DISPLAY INVISIBLE (7460 4410);
FORCEPROP 1 LASTPIN (7450 4400) BN 0
J 2
(7462 4408);
DISPLAY 0.680851 (7462 4408);
PAINT GREEN (7462 4408);
FORCEPROP 1 LAST HDL_TAP TRUE
J 2
(7075 4275);
DISPLAY 0.872340 (7075 4275);
PAINT GREEN (7075 4275);
DISPLAY INVISIBLE (7075 4275);
FORCEPROP 1 LAST BODY_TYPE PLUMBING
J 2
(7400 4450);
DISPLAY 0.872340 (7400 4450);
PAINT GREEN (7400 4450);
DISPLAY INVISIBLE (7400 4450);
FORCEPROP 2 LAST CDS_LIB standard
J 0
(7400 4400);
DISPLAY INVISIBLE (7400 4400);
FORCEPROP 1 LAST PATH I233
J 2
(7402 4400);
DISPLAY 0.872340 (7402 4400);
PAINT GREEN (7402 4400);
DISPLAY INVISIBLE (7402 4400);
FORCEADD TAP..1
R 2
(7250 4350);
FORCEPROP 3 LASTPIN (7300 4350) SIG_NAME P3E_PCH_M2_RX_DN<0>
J 0
(7310 4360);
DISPLAY 0.659574 (7310 4360);
PAINT MONO (7310 4360);
DISPLAY INVISIBLE (7310 4360);
FORCEPROP 1 LASTPIN (7300 4350) BN 0
J 2
(7312 4358);
DISPLAY 0.680851 (7312 4358);
PAINT GREEN (7312 4358);
FORCEPROP 1 LAST HDL_TAP TRUE
J 2
(6925 4225);
DISPLAY 0.872340 (6925 4225);
PAINT GREEN (6925 4225);
DISPLAY INVISIBLE (6925 4225);
FORCEPROP 1 LAST BODY_TYPE PLUMBING
J 2
(7250 4400);
DISPLAY 0.872340 (7250 4400);
PAINT GREEN (7250 4400);
DISPLAY INVISIBLE (7250 4400);
FORCEPROP 2 LAST CDS_LIB standard
J 0
(7250 4350);
DISPLAY INVISIBLE (7250 4350);
FORCEPROP 1 LAST PATH I234
J 2
(7252 4350);
DISPLAY 0.872340 (7252 4350);
PAINT GREEN (7252 4350);
DISPLAY INVISIBLE (7252 4350);
FORCEADD TAP..1
R 2
(7250 4100);
FORCEPROP 3 LASTPIN (7300 4100) SIG_NAME P3E_PCH_M2_RX_DN<1>
J 0
(7310 4110);
DISPLAY 0.659574 (7310 4110);
PAINT MONO (7310 4110);
DISPLAY INVISIBLE (7310 4110);
FORCEPROP 1 LASTPIN (7300 4100) BN 1
J 2
(7312 4108);
DISPLAY 0.680851 (7312 4108);
PAINT GREEN (7312 4108);
FORCEPROP 1 LAST HDL_TAP TRUE
J 2
(6925 3975);
DISPLAY 0.872340 (6925 3975);
PAINT GREEN (6925 3975);
DISPLAY INVISIBLE (6925 3975);
FORCEPROP 1 LAST BODY_TYPE PLUMBING
J 2
(7250 4150);
DISPLAY 0.872340 (7250 4150);
PAINT GREEN (7250 4150);
DISPLAY INVISIBLE (7250 4150);
FORCEPROP 2 LAST CDS_LIB standard
J 0
(7250 4100);
DISPLAY INVISIBLE (7250 4100);
FORCEPROP 1 LAST PATH I235
J 2
(7252 4100);
DISPLAY 0.872340 (7252 4100);
PAINT GREEN (7252 4100);
DISPLAY INVISIBLE (7252 4100);
FORCEADD TAP..1
R 2
(7400 4150);
FORCEPROP 3 LASTPIN (7450 4150) SIG_NAME P3E_PCH_M2_RX_DP<1>
J 0
(7460 4160);
DISPLAY 0.659574 (7460 4160);
PAINT MONO (7460 4160);
DISPLAY INVISIBLE (7460 4160);
FORCEPROP 1 LASTPIN (7450 4150) BN 1
J 2
(7462 4158);
DISPLAY 0.680851 (7462 4158);
PAINT GREEN (7462 4158);
FORCEPROP 1 LAST HDL_TAP TRUE
J 2
(7075 4025);
DISPLAY 0.872340 (7075 4025);
PAINT GREEN (7075 4025);
DISPLAY INVISIBLE (7075 4025);
FORCEPROP 1 LAST BODY_TYPE PLUMBING
J 2
(7400 4200);
DISPLAY 0.872340 (7400 4200);
PAINT GREEN (7400 4200);
DISPLAY INVISIBLE (7400 4200);
FORCEPROP 2 LAST CDS_LIB standard
J 0
(7400 4150);
DISPLAY INVISIBLE (7400 4150);
FORCEPROP 1 LAST PATH I236
J 2
(7402 4150);
DISPLAY 0.872340 (7402 4150);
PAINT GREEN (7402 4150);
DISPLAY INVISIBLE (7402 4150);
FORCEADD TAP..1
R 2
(7400 3900);
FORCEPROP 3 LASTPIN (7450 3900) SIG_NAME P3E_PCH_M2_RX_DP<2>
J 0
(7460 3910);
DISPLAY 0.659574 (7460 3910);
PAINT MONO (7460 3910);
DISPLAY INVISIBLE (7460 3910);
FORCEPROP 1 LASTPIN (7450 3900) BN 2
J 2
(7462 3908);
DISPLAY 0.680851 (7462 3908);
PAINT GREEN (7462 3908);
FORCEPROP 1 LAST HDL_TAP TRUE
J 2
(7075 3775);
DISPLAY 0.872340 (7075 3775);
PAINT GREEN (7075 3775);
DISPLAY INVISIBLE (7075 3775);
FORCEPROP 1 LAST BODY_TYPE PLUMBING
J 2
(7400 3950);
DISPLAY 0.872340 (7400 3950);
PAINT GREEN (7400 3950);
DISPLAY INVISIBLE (7400 3950);
FORCEPROP 2 LAST CDS_LIB standard
J 0
(7400 3900);
DISPLAY INVISIBLE (7400 3900);
FORCEPROP 1 LAST PATH I237
J 2
(7402 3900);
DISPLAY 0.872340 (7402 3900);
PAINT GREEN (7402 3900);
DISPLAY INVISIBLE (7402 3900);
FORCEADD TAP..1
R 2
(7250 3850);
FORCEPROP 3 LASTPIN (7300 3850) SIG_NAME P3E_PCH_M2_RX_DN<2>
J 0
(7310 3860);
DISPLAY 0.659574 (7310 3860);
PAINT MONO (7310 3860);
DISPLAY INVISIBLE (7310 3860);
FORCEPROP 1 LASTPIN (7300 3850) BN 2
J 2
(7312 3858);
DISPLAY 0.680851 (7312 3858);
PAINT GREEN (7312 3858);
FORCEPROP 1 LAST HDL_TAP TRUE
J 2
(6925 3725);
DISPLAY 0.872340 (6925 3725);
PAINT GREEN (6925 3725);
DISPLAY INVISIBLE (6925 3725);
FORCEPROP 1 LAST BODY_TYPE PLUMBING
J 2
(7250 3900);
DISPLAY 0.872340 (7250 3900);
PAINT GREEN (7250 3900);
DISPLAY INVISIBLE (7250 3900);
FORCEPROP 2 LAST CDS_LIB standard
J 0
(7250 3850);
DISPLAY INVISIBLE (7250 3850);
FORCEPROP 1 LAST PATH I238
J 2
(7252 3850);
DISPLAY 0.872340 (7252 3850);
PAINT GREEN (7252 3850);
DISPLAY INVISIBLE (7252 3850);
FORCEADD OFFPAGE..2
(10625 3850);
FORCEPROP 2 LAST $XR0 181 
J 0
(10814 3850);
DISPLAY 0.638298 (10814 3850);
PAINT MONO (10814 3850);
FORCEPROP 1 LAST COMMENT_BODY TRUE
J 0
(10580 3755);
DISPLAY 0.872340 (10580 3755);
PAINT GREEN (10580 3755);
DISPLAY INVISIBLE (10580 3755);
FORCEPROP 1 LAST OFFPAGE TRUE
J 0
(10950 3725);
DISPLAY 0.872340 (10950 3725);
PAINT GREEN (10950 3725);
DISPLAY INVISIBLE (10950 3725);
FORCEPROP 2 LAST PATH I244
J 0
(10825 3900);
DISPLAY 1.021277 (10825 3900);
DISPLAY INVISIBLE (10825 3900);
FORCEPROP 2 LAST CDS_LIB standard
J 0
(10625 3850);
PAINT MONO (10625 3850);
DISPLAY INVISIBLE (10625 3850);
FORCEADD OFFPAGE..2
(10625 3900);
FORCEPROP 2 LAST $XR0 181 
J 0
(10814 3900);
DISPLAY 0.638298 (10814 3900);
PAINT MONO (10814 3900);
FORCEPROP 2 LAST PATH I245
J 0
(10825 3950);
DISPLAY 1.021277 (10825 3950);
DISPLAY INVISIBLE (10825 3950);
FORCEPROP 1 LAST OFFPAGE TRUE
J 0
(10950 3775);
DISPLAY 0.872340 (10950 3775);
PAINT GREEN (10950 3775);
DISPLAY INVISIBLE (10950 3775);
FORCEPROP 1 LAST COMMENT_BODY TRUE
J 0
(10580 3805);
DISPLAY 0.872340 (10580 3805);
PAINT GREEN (10580 3805);
DISPLAY INVISIBLE (10580 3805);
FORCEPROP 2 LAST CDS_LIB standard
J 0
(10625 3900);
PAINT MONO (10625 3900);
DISPLAY INVISIBLE (10625 3900);
FORCEADD Q_RES..1
(10600 3500);
FORCEPROP 1 LAST PART_NUMBER CS00002JB13
J 0
(10475 3575);
DISPLAY 0.638298 (10475 3575);
DISPLAY INVISIBLE (10475 3575);
FORCEPROP 1 LAST TOLERANCE 5%
J 0
(10825 3500);
DISPLAY 0.638298 (10825 3500);
FORCEPROP 1 LAST VALUE 0
J 2
(10800 3500);
DISPLAY 0.638298 (10800 3500);
FORCEPROP 1 LAST MATERIAL CHIP
J 0
(10900 3500);
DISPLAY 0.638298 (10900 3500);
FORCEPROP 1 LAST $LOCATION R2526
J 0
(10375 3500);
DISPLAY 0.638298 (10375 3500);
FORCEPROP 1 LASTPIN (10500 3500) $PN 1
J 0
(10512 3512);
DISPLAY 0.787234 (10512 3512);
PAINT MONO (10512 3512);
FORCEPROP 1 LASTPIN (10700 3500) $PN 2
J 0
(10662 3512);
DISPLAY 0.787234 (10662 3512);
PAINT MONO (10662 3512);
FORCEPROP 1 LAST WATTAGE 1/16W
J 2
(10775 3625);
DISPLAY 0.638298 (10775 3625);
DISPLAY INVISIBLE (10775 3625);
FORCEPROP 1 LAST PACK_TYPE 0402LF
J 0
(10875 3500);
DISPLAY 0.638298 (10875 3500);
DISPLAY INVISIBLE (10875 3500);
FORCEPROP 1 LAST PATH I247
J 0
(10550 3650);
DISPLAY 0.978723 (10550 3650);
PAINT WHITE (10550 3650);
DISPLAY INVISIBLE (10550 3650);
FORCEPROP 2 LAST CDS_LIB pure_quanta
J 0
(10600 3500);
DISPLAY INVISIBLE (10600 3500);
FORCEPROP 0 LAST CDS_LOCATION R2526
J 0
(10900 3550);
DISPLAY 1.021277 (10900 3550);
DISPLAY INVISIBLE (10900 3550);
FORCEPROP 0 LAST $SEC 1
J 0
(10900 3550);
DISPLAY 0.680851 (10900 3550);
PAINT MONO (10900 3550);
DISPLAY INVISIBLE (10900 3550);
FORCEPROP 0 LAST CDS_SEC 1
J 0
(10900 3550);
DISPLAY 1.021277 (10900 3550);
DISPLAY INVISIBLE (10900 3550);
FORCEADD OFFPAGE..2
(12025 3500);
FORCEPROP 2 LAST $XR0 184 
J 0
(12214 3500);
DISPLAY 0.638298 (12214 3500);
PAINT MONO (12214 3500);
FORCEPROP 2 LAST CDS_LIB standard
J 0
(12025 3500);
DISPLAY INVISIBLE (12025 3500);
FORCEPROP 2 LAST PATH I248
J 0
(12225 3550);
DISPLAY 1.021277 (12225 3550);
DISPLAY INVISIBLE (12225 3550);
FORCEPROP 1 LAST OFFPAGE TRUE
J 0
(12350 3375);
DISPLAY 0.872340 (12350 3375);
PAINT GREEN (12350 3375);
DISPLAY INVISIBLE (12350 3375);
FORCEPROP 1 LAST COMMENT_BODY TRUE
J 0
(11980 3405);
DISPLAY 0.872340 (11980 3405);
PAINT GREEN (11980 3405);
DISPLAY INVISIBLE (11980 3405);
FORCEADD UNIVERSAL_POWER..1
(11175 3350);
FORCEPROP 3 LASTPIN (11175 3300) SIG_NAME P3V3_AUX\g
J 0
(11185 3310);
DISPLAY 0.659574 (11185 3310);
PAINT MONO (11185 3310);
DISPLAY INVISIBLE (11185 3310);
FORCEPROP 1 LAST HDL_POWER P3V3_AUX
J 1
(11175 3400);
DISPLAY 0.702128 (11175 3400);
PAINT GREEN (11175 3400);
FORCEPROP 1 LAST PATH I249
J 0
(11225 3375);
DISPLAY 0.872340 (11225 3375);
PAINT AQUA (11225 3375);
DISPLAY INVISIBLE (11225 3375);
FORCEPROP 2 LAST CDS_LIB logical_power
J 0
(11175 3350);
PAINT MONO (11175 3350);
DISPLAY INVISIBLE (11175 3350);
FORCEADD OFFPAGE..2
(10625 3600);
FORCEPROP 2 LAST $XR0 190 
J 0
(10814 3600);
DISPLAY 0.638298 (10814 3600);
PAINT MONO (10814 3600);
FORCEPROP 2 LAST PATH I250
J 0
(10800 3675);
DISPLAY 1.021277 (10800 3675);
DISPLAY INVISIBLE (10800 3675);
FORCEPROP 2 LAST CDS_LIB standard
J 0
(10625 3600);
DISPLAY INVISIBLE (10625 3600);
FORCEPROP 1 LAST COMMENT_BODY TRUE
J 0
(10580 3505);
DISPLAY 0.872340 (10580 3505);
PAINT GREEN (10580 3505);
DISPLAY INVISIBLE (10580 3505);
FORCEPROP 1 LAST OFFPAGE TRUE
J 0
(10950 3475);
DISPLAY 0.872340 (10950 3475);
PAINT GREEN (10950 3475);
DISPLAY INVISIBLE (10950 3475);
FORCEADD OFFPAGE..5
(6175 3300);
FORCEPROP 2 LAST $XR2 182 
J 0
(5680 3300);
DISPLAY 0.638298 (5680 3300);
PAINT MONO (5680 3300);
FORCEPROP 2 LAST $XR1 161 
J 0
(5800 3300);
DISPLAY 0.638298 (5800 3300);
PAINT MONO (5800 3300);
FORCEPROP 2 LAST $XR0 155 
J 0
(5920 3300);
DISPLAY 0.638298 (5920 3300);
PAINT MONO (5920 3300);
FORCEPROP 2 LAST CDS_LIB standard
J 0
(6175 3300);
DISPLAY INVISIBLE (6175 3300);
FORCEPROP 1 LAST OFFPAGE TRUE
J 0
(6500 3175);
DISPLAY 0.872340 (6500 3175);
DISPLAY INVISIBLE (6500 3175);
FORCEPROP 1 LAST COMMENT_BODY TRUE
J 0
(6275 3225);
DISPLAY 0.872340 (6275 3225);
PAINT GREEN (6275 3225);
DISPLAY INVISIBLE (6275 3225);
FORCEPROP 2 LAST PATH I296
J 0
(6225 3375);
DISPLAY 1.021277 (6225 3375);
DISPLAY INVISIBLE (6225 3375);
FORCEADD Q_RES..1
(6975 3300);
FORCEPROP 1 LAST PART_NUMBER CS03322FB03
J 0
(6850 3250);
DISPLAY 0.510638 (6850 3250);
DISPLAY INVISIBLE (6850 3250);
FORCEPROP 1 LAST VALUE 33.2
J 2
(7175 3300);
DISPLAY 0.510638 (7175 3300);
FORCEPROP 1 LAST TOLERANCE 1%
J 0
(7200 3300);
DISPLAY 0.510638 (7200 3300);
FORCEPROP 1 LAST MATERIAL CHIP
J 0
(7275 3300);
DISPLAY 0.510638 (7275 3300);
FORCEPROP 1 LAST LOCATION R3301
J 0
(6800 3300);
DISPLAY 0.510638 (6800 3300);
FORCEPROP 1 LASTPIN (6875 3300) $PN 1
J 0
(6887 3312);
DISPLAY 0.787234 (6887 3312);
PAINT MONO (6887 3312);
FORCEPROP 1 LASTPIN (7075 3300) $PN 2
J 0
(7037 3312);
DISPLAY 0.787234 (7037 3312);
PAINT MONO (7037 3312);
FORCEPROP 1 LAST PACK_TYPE 0402LF
J 0
(6850 3425);
DISPLAY 0.510638 (6850 3425);
DISPLAY INVISIBLE (6850 3425);
FORCEPROP 1 LAST WATTAGE 1/16W
J 2
(7150 3425);
DISPLAY 0.510638 (7150 3425);
DISPLAY INVISIBLE (7150 3425);
FORCEPROP 1 LAST PATH I299
J 0
(6925 3450);
DISPLAY 0.978723 (6925 3450);
PAINT WHITE (6925 3450);
DISPLAY INVISIBLE (6925 3450);
FORCEPROP 2 LAST CDS_LIB pure_quanta
J 0
(6975 3300);
DISPLAY INVISIBLE (6975 3300);
FORCEPROP 0 LAST $SEC 1
J 0
(7275 3325);
DISPLAY 0.680851 (7275 3325);
PAINT MONO (7275 3325);
DISPLAY INVISIBLE (7275 3325);
FORCEPROP 0 LAST CDS_SEC 1
J 0
(7275 3325);
DISPLAY 1.021277 (7275 3325);
DISPLAY INVISIBLE (7275 3325);
FORCEADD UNIVERSAL_POWER..1
(9475 4650);
FORCEPROP 3 LASTPIN (9475 4600) SIG_NAME P3V3_M2_0\g
J 0
(9485 4610);
DISPLAY 0.659574 (9485 4610);
PAINT MONO (9485 4610);
DISPLAY INVISIBLE (9485 4610);
FORCEPROP 1 LAST HDL_POWER P3V3_M2_0
J 1
(9475 4700);
DISPLAY 0.872340 (9475 4700);
PAINT GREEN (9475 4700);
FORCEPROP 2 LAST CDS_LIB logical_power
J 0
(9475 4650);
DISPLAY INVISIBLE (9475 4650);
FORCEPROP 1 LAST PATH I300
J 0
(9525 4675);
DISPLAY 0.872340 (9525 4675);
PAINT AQUA (9525 4675);
DISPLAY INVISIBLE (9525 4675);
FORCEADD UNIVERSAL_GND..1
(8050 -1050);
FORCEPROP 3 LASTPIN (8050 -1000) SIG_NAME GND\g
J 0
(8060 -990);
DISPLAY 0.659574 (8060 -990);
PAINT MONO (8060 -990);
DISPLAY INVISIBLE (8060 -990);
FORCEPROP 1 LAST HDL_POWER GND
J 1
(8075 -1125);
DISPLAY 0.872340 (8075 -1125);
PAINT GREEN (8075 -1125);
DISPLAY INVISIBLE (8075 -1125);
FORCEPROP 2 LAST CDS_LIB logical_power
J 0
(8050 -1050);
DISPLAY INVISIBLE (8050 -1050);
FORCEPROP 1 LAST PATH I301
J 0
(8125 -1050);
DISPLAY 0.872340 (8125 -1050);
PAINT AQUA (8125 -1050);
DISPLAY INVISIBLE (8125 -1050);
FORCEADD OFFPAGE..2
(11500 1175);
FORCEPROP 2 LAST $XR1 240 
J 0
(11809 1175);
DISPLAY 0.638298 (11809 1175);
PAINT MONO (11809 1175);
FORCEPROP 2 LAST $XR0 214 
J 0
(11689 1175);
DISPLAY 0.638298 (11689 1175);
PAINT MONO (11689 1175);
FORCEPROP 2 LAST PATH I302
J 0
(11700 1225);
DISPLAY 1.021277 (11700 1225);
DISPLAY INVISIBLE (11700 1225);
FORCEPROP 2 LAST CDS_LIB standard
J 0
(11500 1175);
DISPLAY INVISIBLE (11500 1175);
FORCEPROP 1 LAST OFFPAGE TRUE
J 0
(11825 1050);
DISPLAY 0.872340 (11825 1050);
PAINT AQUA (11825 1050);
DISPLAY INVISIBLE (11825 1050);
FORCEPROP 1 LAST COMMENT_BODY TRUE
J 0
(11455 1080);
DISPLAY 0.872340 (11455 1080);
PAINT GREEN (11455 1080);
DISPLAY INVISIBLE (11455 1080);
FORCEADD Q_RES..2
R 2
(10300 925);
FORCEPROP 1 LAST PART_NUMBER CS31002FB08
J 2
(10260 800);
DISPLAY 0.510638 (10260 800);
DISPLAY INVISIBLE (10260 800);
FORCEPROP 1 LAST WATTAGE 1/16W
J 2
(10260 900);
DISPLAY 0.510638 (10260 900);
FORCEPROP 1 LAST TOLERANCE 1%
J 2
(10255 950);
DISPLAY 0.510638 (10255 950);
FORCEPROP 1 LAST VALUE 10K
J 2
(10255 1000);
DISPLAY 0.510638 (10255 1000);
FORCEPROP 1 LAST MATERIAL CHIP
J 2
(10260 850);
DISPLAY 0.510638 (10260 850);
FORCEPROP 1 LAST PACK_TYPE 0402LF
J 2
(10260 750);
DISPLAY 0.510638 (10260 750);
FORCEPROP 1 LAST $LOCATION R3297
J 2
(10255 1050);
DISPLAY 0.978723 (10255 1050);
FORCEPROP 1 LASTPIN (10300 1025) $PN 1
J 2
(10295 987);
DISPLAY 0.787234 (10295 987);
PAINT MONO (10295 987);
FORCEPROP 1 LASTPIN (10300 825) $PN 2
J 2
(10295 835);
DISPLAY 0.787234 (10295 835);
PAINT MONO (10295 835);
FORCEPROP 1 LAST PATH I303
J 2
(10250 1100);
DISPLAY 0.978723 (10250 1100);
PAINT WHITE (10250 1100);
DISPLAY INVISIBLE (10250 1100);
FORCEPROP 2 LAST CDS_LIB pure_quanta
J 0
(10300 925);
DISPLAY INVISIBLE (10300 925);
FORCEPROP 0 LAST CDS_LOCATION R3297
J 0
(10275 1100);
DISPLAY 1.021277 (10275 1100);
DISPLAY INVISIBLE (10275 1100);
FORCEPROP 0 LAST $SEC 1
J 0
(10275 1100);
DISPLAY 0.680851 (10275 1100);
PAINT MONO (10275 1100);
DISPLAY INVISIBLE (10275 1100);
FORCEPROP 0 LAST CDS_SEC 1
J 0
(10275 1100);
DISPLAY 1.021277 (10275 1100);
DISPLAY INVISIBLE (10275 1100);
FORCEADD UNIVERSAL_GND..1
(10300 675);
FORCEPROP 3 LASTPIN (10300 725) SIG_NAME GND\g
J 0
(10310 735);
DISPLAY 0.659574 (10310 735);
PAINT MONO (10310 735);
DISPLAY INVISIBLE (10310 735);
FORCEPROP 1 LAST PATH I304
J 0
(10375 675);
DISPLAY 0.872340 (10375 675);
PAINT AQUA (10375 675);
DISPLAY INVISIBLE (10375 675);
FORCEPROP 2 LAST CDS_LIB logical_power
J 0
(10300 675);
DISPLAY INVISIBLE (10300 675);
FORCEPROP 1 LAST HDL_POWER GND
J 1
(10325 600);
DISPLAY 0.872340 (10325 600);
PAINT GREEN (10325 600);
DISPLAY INVISIBLE (10325 600);
FORCEADD UNIVERSAL_POWER..1
(10725 700);
FORCEPROP 3 LASTPIN (10725 650) SIG_NAME P3V3_AUX\g
J 0
(10735 660);
DISPLAY 0.659574 (10735 660);
PAINT MONO (10735 660);
DISPLAY INVISIBLE (10735 660);
FORCEPROP 1 LAST HDL_POWER P3V3_AUX
J 1
(10725 750);
DISPLAY 0.723404 (10725 750);
PAINT GREEN (10725 750);
FORCEPROP 1 LAST PATH I305
J 0
(10775 725);
DISPLAY 0.872340 (10775 725);
PAINT AQUA (10775 725);
DISPLAY INVISIBLE (10775 725);
FORCEPROP 2 LAST CDS_LIB logical_power
J 0
(10725 700);
DISPLAY INVISIBLE (10725 700);
FORCEADD Q_RES..2
R 2
(10725 500);
FORCEPROP 1 LAST PART_NUMBER CS31002FB08
J 2
(10685 375);
DISPLAY 0.510638 (10685 375);
DISPLAY INVISIBLE (10685 375);
FORCEPROP 1 LAST VALUE 10K
J 2
(10680 575);
DISPLAY 0.510638 (10680 575);
FORCEPROP 1 LAST MATERIAL CHIP
J 2
(10685 425);
DISPLAY 0.510638 (10685 425);
FORCEPROP 1 LAST WATTAGE 1/16W
J 2
(10685 475);
DISPLAY 0.510638 (10685 475);
FORCEPROP 1 LAST PACK_TYPE 0402LF
J 2
(10685 325);
DISPLAY 0.510638 (10685 325);
FORCEPROP 1 LAST TOLERANCE 1%
J 2
(10680 525);
DISPLAY 0.510638 (10680 525);
FORCEPROP 1 LAST $LOCATION R3298
J 2
(10680 625);
DISPLAY 0.978723 (10680 625);
FORCEPROP 1 LASTPIN (10725 600) $PN 1
J 2
(10720 562);
DISPLAY 0.787234 (10720 562);
PAINT MONO (10720 562);
FORCEPROP 1 LASTPIN (10725 400) $PN 2
J 2
(10720 410);
DISPLAY 0.787234 (10720 410);
PAINT MONO (10720 410);
FORCEPROP 1 LAST PATH I306
J 2
(10675 675);
DISPLAY 0.978723 (10675 675);
PAINT WHITE (10675 675);
DISPLAY INVISIBLE (10675 675);
FORCEPROP 2 LAST CDS_LIB pure_quanta
J 0
(10725 500);
DISPLAY INVISIBLE (10725 500);
FORCEPROP 0 LAST CDS_LOCATION R3298
J 0
(10700 675);
DISPLAY 1.021277 (10700 675);
DISPLAY INVISIBLE (10700 675);
FORCEPROP 0 LAST $SEC 1
J 0
(10700 675);
DISPLAY 0.680851 (10700 675);
PAINT MONO (10700 675);
DISPLAY INVISIBLE (10700 675);
FORCEPROP 0 LAST CDS_SEC 1
J 0
(10700 675);
DISPLAY 1.021277 (10700 675);
DISPLAY INVISIBLE (10700 675);
FORCEADD UNIVERSAL_POWER..1
(9350 1875);
FORCEPROP 3 LASTPIN (9350 1825) SIG_NAME P3V3_AUX\g
J 0
(9360 1835);
DISPLAY 0.659574 (9360 1835);
PAINT MONO (9360 1835);
DISPLAY INVISIBLE (9360 1835);
FORCEPROP 1 LAST HDL_POWER P3V3_AUX
J 1
(9350 1925);
DISPLAY 0.723404 (9350 1925);
PAINT GREEN (9350 1925);
FORCEPROP 1 LAST PATH I307
J 0
(9400 1900);
DISPLAY 0.872340 (9400 1900);
PAINT AQUA (9400 1900);
DISPLAY INVISIBLE (9400 1900);
FORCEPROP 2 LAST CDS_LIB logical_power
J 0
(9350 1875);
DISPLAY INVISIBLE (9350 1875);
FORCEADD Q_CAP..1
(9600 1525);
FORCEPROP 1 LAST PART_NUMBER CH4104K1B00
J 0
(9650 1375);
DISPLAY 0.617021 (9650 1375);
DISPLAY INVISIBLE (9650 1375);
FORCEPROP 1 LAST MATERIAL X7R
J 0
(9650 1425);
DISPLAY 0.617021 (9650 1425);
FORCEPROP 1 LAST PACK_TYPE 0402
J 0
(9650 1325);
DISPLAY 0.617021 (9650 1325);
FORCEPROP 1 LAST TOLERANCE 10%
J 0
(9650 1475);
DISPLAY 0.617021 (9650 1475);
FORCEPROP 1 LAST VOLTAGE 25V
J 0
(9650 1525);
DISPLAY 0.617021 (9650 1525);
FORCEPROP 1 LAST VALUE 0.1UF
J 0
(9650 1575);
DISPLAY 0.617021 (9650 1575);
FORCEPROP 1 LAST $LOCATION C1873
J 0
(9650 1625);
DISPLAY 0.978723 (9650 1625);
FORCEPROP 1 LASTPIN (9600 1625) $PN 1
J 0
(9610 1605);
DISPLAY 0.787234 (9610 1605);
PAINT MONO (9610 1605);
FORCEPROP 1 LASTPIN (9600 1425) $PN 2
J 0
(9610 1405);
DISPLAY 0.787234 (9610 1405);
PAINT MONO (9610 1405);
FORCEPROP 1 LAST PATH I308
J 0
(9650 1675);
DISPLAY 0.978723 (9650 1675);
PAINT WHITE (9650 1675);
DISPLAY INVISIBLE (9650 1675);
FORCEPROP 2 LAST BOM_COST VR_SYSTEM 
J 0
(9650 1675);
DISPLAY 0.680851 (9650 1675);
DISPLAY INVISIBLE (9650 1675);
FORCEPROP 2 LAST CDS_LIB pure_quanta
J 0
(9600 1525);
DISPLAY INVISIBLE (9600 1525);
FORCEPROP 0 LAST CDS_LOCATION C1873
J 0
(9650 1675);
DISPLAY 1.021277 (9650 1675);
DISPLAY INVISIBLE (9650 1675);
FORCEPROP 0 LAST $SEC 1
J 0
(9650 1675);
DISPLAY 0.680851 (9650 1675);
PAINT MONO (9650 1675);
DISPLAY INVISIBLE (9650 1675);
FORCEPROP 0 LAST CDS_SEC 1
J 0
(9650 1675);
DISPLAY 1.021277 (9650 1675);
DISPLAY INVISIBLE (9650 1675);
FORCEADD UNIVERSAL_GND..1
(9600 1275);
FORCEPROP 3 LASTPIN (9600 1325) SIG_NAME GND\g
J 0
(9610 1335);
DISPLAY 0.659574 (9610 1335);
PAINT MONO (9610 1335);
DISPLAY INVISIBLE (9610 1335);
FORCEPROP 1 LAST PATH I309
J 0
(9675 1275);
DISPLAY 0.872340 (9675 1275);
PAINT AQUA (9675 1275);
DISPLAY INVISIBLE (9675 1275);
FORCEPROP 1 LAST HDL_POWER GND
J 1
(9625 1200);
DISPLAY 0.872340 (9625 1200);
PAINT GREEN (9625 1200);
DISPLAY INVISIBLE (9625 1200);
FORCEPROP 2 LAST CDS_LIB logical_power
J 0
(9600 1275);
DISPLAY INVISIBLE (9600 1275);
FORCEADD UNIVERSAL_GND..1
(9350 775);
FORCEPROP 3 LASTPIN (9350 825) SIG_NAME GND\g
J 0
(9360 835);
DISPLAY 0.659574 (9360 835);
PAINT MONO (9360 835);
DISPLAY INVISIBLE (9360 835);
FORCEPROP 1 LAST PATH I310
J 0
(9425 775);
DISPLAY 0.872340 (9425 775);
PAINT AQUA (9425 775);
DISPLAY INVISIBLE (9425 775);
FORCEPROP 1 LAST HDL_POWER GND
J 1
(9375 700);
DISPLAY 0.872340 (9375 700);
PAINT GREEN (9375 700);
DISPLAY INVISIBLE (9375 700);
FORCEPROP 2 LAST CDS_LIB logical_power
J 0
(9350 775);
DISPLAY INVISIBLE (9350 775);
FORCEADD OFFPAGE..2
(12500 250);
FORCEPROP 2 LAST $XR0 190 
J 0
(12689 250);
DISPLAY 0.638298 (12689 250);
PAINT MONO (12689 250);
FORCEPROP 2 LAST PATH I311
J 0
(12700 300);
DISPLAY 1.021277 (12700 300);
DISPLAY INVISIBLE (12700 300);
FORCEPROP 1 LAST COMMENT_BODY TRUE
J 0
(12455 155);
DISPLAY 0.872340 (12455 155);
PAINT GREEN (12455 155);
DISPLAY INVISIBLE (12455 155);
FORCEPROP 1 LAST OFFPAGE TRUE
J 0
(12825 125);
DISPLAY 0.872340 (12825 125);
PAINT AQUA (12825 125);
DISPLAY INVISIBLE (12825 125);
FORCEPROP 2 LAST CDS_LIB standard
J 0
(12500 250);
DISPLAY INVISIBLE (12500 250);
FORCEADD Q_RES..1
(11000 250);
FORCEPROP 1 LAST PART_NUMBER CS00002JB13
J 0
(11075 150);
DISPLAY 0.723404 (11075 150);
DISPLAY INVISIBLE (11075 150);
FORCEPROP 1 LAST VALUE 0
J 2
(10825 200);
DISPLAY 0.723404 (10825 200);
FORCEPROP 1 LAST TOLERANCE 5%
J 0
(10875 200);
DISPLAY 0.723404 (10875 200);
FORCEPROP 1 LAST WATTAGE 1/16W
J 2
(11475 250);
DISPLAY 0.723404 (11475 250);
FORCEPROP 1 LAST MATERIAL CHIP
J 0
(11075 200);
DISPLAY 0.723404 (11075 200);
FORCEPROP 1 LAST PACK_TYPE 0402LF
J 0
(11075 250);
DISPLAY 0.723404 (11075 250);
FORCEPROP 1 LAST $LOCATION R5377
J 0
(10875 275);
DISPLAY 0.723404 (10875 275);
FORCEPROP 1 LAST PATH I312
J 0
(10950 400);
DISPLAY 0.978723 (10950 400);
PAINT WHITE (10950 400);
DISPLAY INVISIBLE (10950 400);
FORCEPROP 2 LAST CDS_LIB pure_quanta
J 0
(11000 250);
DISPLAY INVISIBLE (11000 250);
FORCEPROP 0 LAST CDS_LOCATION R5377
J 0
(10875 325);
DISPLAY INVISIBLE (10875 325);
FORCEPROP 0 LAST $SEC 1
J 0
(10875 325);
DISPLAY INVISIBLE (10875 325);
FORCEPROP 0 LAST CDS_SEC 1
J 0
(10875 325);
DISPLAY INVISIBLE (10875 325);
FORCEPROP 1 LASTPIN (10900 250) $PN 1
J 0
(10912 262);
DISPLAY 0.787234 (10912 262);
PAINT MONO (10912 262);
DISPLAY INVISIBLE (10912 262);
FORCEPROP 1 LASTPIN (11100 250) $PN 2
J 0
(11062 262);
DISPLAY 0.787234 (11062 262);
PAINT MONO (11062 262);
DISPLAY INVISIBLE (11062 262);
FORCEADD UNIVERSAL_GND..1
(9850 -400);
FORCEPROP 3 LASTPIN (9850 -350) SIG_NAME GND\g
J 0
(9860 -340);
DISPLAY 0.659574 (9860 -340);
PAINT MONO (9860 -340);
DISPLAY INVISIBLE (9860 -340);
FORCEPROP 1 LAST HDL_POWER GND
J 1
(9875 -475);
DISPLAY 0.872340 (9875 -475);
PAINT GREEN (9875 -475);
DISPLAY INVISIBLE (9875 -475);
FORCEPROP 2 LAST CDS_LIB logical_power
J 0
(9850 -400);
DISPLAY INVISIBLE (9850 -400);
FORCEPROP 1 LAST PATH I313
J 0
(9925 -400);
DISPLAY 0.872340 (9925 -400);
PAINT AQUA (9925 -400);
DISPLAY INVISIBLE (9925 -400);
FORCEADD 74LVC1G126SE7..1
(9350 1175);
FORCEPROP 1 LAST PART_NUMBER AL1G0126009
J 0
(9456 859);
DISPLAY 0.723404 (9456 859);
PAINT GREEN (9456 859);
DISPLAY INVISIBLE (9456 859);
FORCEPROP 2 LAST VALUE 74LVC1G126SE-7
J 0
(9450 900);
DISPLAY 0.638298 (9450 900);
FORCEPROP 2 LAST PART_TYPE SMLF
J 0
(9450 950);
DISPLAY 0.638298 (9450 950);
FORCEPROP 1 LAST MATERIAL IC
J 0
(9456 732);
DISPLAY 0.723404 (9456 732);
PAINT GREEN (9456 732);
FORCEPROP 1 LAST $LOCATION U239
J 0
(9456 1006);
DISPLAY 0.723404 (9456 1006);
PAINT GREEN (9456 1006);
FORCEPROP 0 LASTPIN (9100 1225) $PN 2
J 2
(9090 1235);
DISPLAY 0.680851 (9090 1235);
PAINT MONO (9090 1235);
FORCEPROP 0 LASTPIN (9350 925) $PN 3
R 1
J 2
(9340 915);
DISPLAY 0.680851 (9340 915);
PAINT MONO (9340 915);
FORCEPROP 0 LASTPIN (9100 1125) $PN 1
J 2
(9090 1135);
DISPLAY 0.680851 (9090 1135);
PAINT MONO (9090 1135);
FORCEPROP 0 LASTPIN (9350 1425) $PN 5
R 1
J 0
(9340 1435);
DISPLAY 0.680851 (9340 1435);
PAINT MONO (9340 1435);
FORCEPROP 0 LASTPIN (9600 1175) $PN 4
J 0
(9610 1185);
DISPLAY 0.680851 (9610 1185);
PAINT MONO (9610 1185);
FORCEPROP 1 LAST PATH I315
J 0
(9350 1175);
DISPLAY 0.723404 (9350 1175);
PAINT GREEN (9350 1175);
DISPLAY INVISIBLE (9350 1175);
FORCEPROP 1 LAST NEEDS_NO_SIZE TRUE
J 0
(9350 1175);
DISPLAY 0.723404 (9350 1175);
PAINT GREEN (9350 1175);
DISPLAY INVISIBLE (9350 1175);
FORCEPROP 1 LAST CDS_LMAN_SYM_OUTLINE -100,100,100,-100
J 0
(9350 1175);
DISPLAY 0.468085 (9350 1175);
PAINT GREEN (9350 1175);
DISPLAY INVISIBLE (9350 1175);
FORCEPROP 2 LAST CDS_LIB pure_quanta
J 0
(9350 1175);
DISPLAY INVISIBLE (9350 1175);
FORCEPROP 0 LAST CDS_LOCATION U239
J 0
(9475 1050);
DISPLAY 1.021277 (9475 1050);
DISPLAY INVISIBLE (9475 1050);
FORCEPROP 0 LAST $SEC 1
J 0
(9475 1050);
DISPLAY 0.680851 (9475 1050);
PAINT MONO (9475 1050);
DISPLAY INVISIBLE (9475 1050);
FORCEPROP 0 LAST CDS_SEC 1
J 0
(9475 1050);
DISPLAY 1.021277 (9475 1050);
DISPLAY INVISIBLE (9475 1050);
FORCEADD Q_RES..2
(7650 1525);
FORCEPROP 1 LAST PART_NUMBER CS24702FB06
J 0
(7690 1400);
DISPLAY 0.787234 (7690 1400);
DISPLAY INVISIBLE (7690 1400);
FORCEPROP 1 LAST PACK_TYPE 0402LF
J 0
(7690 1350);
DISPLAY 0.787234 (7690 1350);
FORCEPROP 1 LAST MATERIAL CHIP
J 0
(7690 1450);
DISPLAY 0.787234 (7690 1450);
FORCEPROP 1 LAST WATTAGE 1/16W
J 0
(7690 1500);
DISPLAY 0.787234 (7690 1500);
FORCEPROP 1 LAST TOLERANCE 1%
J 0
(7695 1550);
DISPLAY 0.787234 (7695 1550);
FORCEPROP 1 LAST VALUE 4.7K
J 0
(7695 1600);
DISPLAY 0.787234 (7695 1600);
FORCEPROP 1 LAST $LOCATION R3295
J 0
(7695 1650);
DISPLAY 0.978723 (7695 1650);
FORCEPROP 1 LASTPIN (7650 1625) $PN 1
J 0
(7655 1587);
DISPLAY 0.787234 (7655 1587);
PAINT MONO (7655 1587);
FORCEPROP 1 LASTPIN (7650 1425) $PN 2
J 0
(7655 1435);
DISPLAY 0.787234 (7655 1435);
PAINT MONO (7655 1435);
FORCEPROP 1 LAST PATH I317
J 0
(7700 1700);
DISPLAY 0.978723 (7700 1700);
PAINT WHITE (7700 1700);
DISPLAY INVISIBLE (7700 1700);
FORCEPROP 2 LAST CDS_LIB pure_quanta
J 0
(7650 1525);
DISPLAY INVISIBLE (7650 1525);
FORCEPROP 0 LAST CDS_LOCATION R3295
J 0
(7700 1700);
DISPLAY 1.021277 (7700 1700);
DISPLAY INVISIBLE (7700 1700);
FORCEPROP 0 LAST $SEC 1
J 0
(7700 1700);
DISPLAY 0.680851 (7700 1700);
PAINT MONO (7700 1700);
DISPLAY INVISIBLE (7700 1700);
FORCEPROP 0 LAST CDS_SEC 1
J 0
(7700 1700);
DISPLAY 1.021277 (7700 1700);
DISPLAY INVISIBLE (7700 1700);
FORCEADD OFFPAGE..1
(7725 1125);
FORCEPROP 2 LAST $XR0 190 
J 0
(7443 1125);
DISPLAY 0.638298 (7443 1125);
PAINT MONO (7443 1125);
FORCEPROP 2 LAST PATH I318
J 0
(7475 1175);
DISPLAY 1.021277 (7475 1175);
DISPLAY INVISIBLE (7475 1175);
FORCEPROP 2 LAST CDS_LIB standard
J 0
(7725 1125);
DISPLAY INVISIBLE (7725 1125);
FORCEPROP 1 LAST OFFPAGE TRUE
J 0
(8050 1000);
DISPLAY 0.872340 (8050 1000);
PAINT AQUA (8050 1000);
DISPLAY INVISIBLE (8050 1000);
FORCEPROP 1 LAST COMMENT_BODY TRUE
J 0
(7850 1025);
DISPLAY 0.872340 (7850 1025);
PAINT GREEN (7850 1025);
DISPLAY INVISIBLE (7850 1025);
FORCEADD Q_RES..1
(7075 1225);
FORCEPROP 1 LAST PART_NUMBER CS00002JB13
J 0
(6950 1300);
DISPLAY 0.638298 (6950 1300);
DISPLAY INVISIBLE (6950 1300);
FORCEPROP 1 LAST VALUE 0
J 2
(7275 1225);
DISPLAY 0.638298 (7275 1225);
FORCEPROP 1 LAST MATERIAL CHIP
J 0
(7375 1225);
DISPLAY 0.638298 (7375 1225);
FORCEPROP 1 LAST TOLERANCE 5%
J 0
(7300 1225);
DISPLAY 0.638298 (7300 1225);
FORCEPROP 1 LAST $LOCATION R3294
J 0
(7025 1275);
DISPLAY 0.978723 (7025 1275);
FORCEPROP 1 LASTPIN (6975 1225) $PN 1
J 0
(6987 1237);
DISPLAY 0.787234 (6987 1237);
PAINT MONO (6987 1237);
FORCEPROP 1 LASTPIN (7175 1225) $PN 2
J 0
(7137 1237);
DISPLAY 0.787234 (7137 1237);
PAINT MONO (7137 1237);
FORCEPROP 2 LAST CDS_LIB pure_quanta
J 0
(7075 1225);
DISPLAY INVISIBLE (7075 1225);
FORCEPROP 1 LAST WATTAGE 1/16W
J 2
(7250 1350);
DISPLAY 0.638298 (7250 1350);
DISPLAY INVISIBLE (7250 1350);
FORCEPROP 1 LAST PACK_TYPE 0402LF
J 0
(7350 1225);
DISPLAY 0.638298 (7350 1225);
DISPLAY INVISIBLE (7350 1225);
FORCEPROP 1 LAST PATH I320
J 0
(7025 1375);
DISPLAY 0.978723 (7025 1375);
PAINT WHITE (7025 1375);
DISPLAY INVISIBLE (7025 1375);
FORCEPROP 0 LAST CDS_LOCATION R3294
J 0
(7025 1325);
DISPLAY 1.021277 (7025 1325);
DISPLAY INVISIBLE (7025 1325);
FORCEPROP 0 LAST $SEC 1
J 0
(7025 1325);
DISPLAY 0.680851 (7025 1325);
PAINT MONO (7025 1325);
DISPLAY INVISIBLE (7025 1325);
FORCEPROP 0 LAST CDS_SEC 1
J 0
(7025 1325);
DISPLAY 1.021277 (7025 1325);
DISPLAY INVISIBLE (7025 1325);
FORCEADD OFFPAGE..1
(6300 1225);
FORCEPROP 2 LAST $XR0 190 
J 0
(6048 1225);
DISPLAY 0.638298 (6048 1225);
PAINT MONO (6048 1225);
FORCEPROP 1 LAST COMMENT_BODY TRUE
J 0
(6425 1125);
DISPLAY 0.872340 (6425 1125);
PAINT GREEN (6425 1125);
DISPLAY INVISIBLE (6425 1125);
FORCEPROP 1 LAST OFFPAGE TRUE
J 0
(6625 1100);
DISPLAY 0.872340 (6625 1100);
PAINT AQUA (6625 1100);
DISPLAY INVISIBLE (6625 1100);
FORCEPROP 2 LAST CDS_LIB standard
J 0
(6300 1225);
PAINT MONO (6300 1225);
DISPLAY INVISIBLE (6300 1225);
FORCEPROP 2 LAST PATH I322
J 0
(6025 1275);
DISPLAY 1.021277 (6025 1275);
DISPLAY INVISIBLE (6025 1275);
FORCEADD UNIVERSAL_POWER..1
(8625 625);
FORCEPROP 3 LASTPIN (8625 575) SIG_NAME P3V3_AUX\g
J 0
(8635 585);
DISPLAY 0.659574 (8635 585);
PAINT MONO (8635 585);
DISPLAY INVISIBLE (8635 585);
FORCEPROP 1 LAST HDL_POWER P3V3_AUX
J 1
(8625 675);
DISPLAY 0.723404 (8625 675);
PAINT GREEN (8625 675);
FORCEPROP 1 LAST PATH I323
J 0
(8675 650);
DISPLAY 0.872340 (8675 650);
PAINT AQUA (8675 650);
DISPLAY INVISIBLE (8675 650);
FORCEPROP 2 LAST CDS_LIB logical_power
J 0
(8625 625);
DISPLAY INVISIBLE (8625 625);
FORCEADD Q_RES..2
(8625 300);
FORCEPROP 1 LAST PART_NUMBER CS24702FB06
J 0
(8665 175);
DISPLAY 0.787234 (8665 175);
DISPLAY INVISIBLE (8665 175);
FORCEPROP 1 LAST WATTAGE 1/16W
J 0
(8665 275);
DISPLAY 0.787234 (8665 275);
FORCEPROP 1 LAST PACK_TYPE 0402LF
J 0
(8665 125);
DISPLAY 0.787234 (8665 125);
FORCEPROP 1 LAST VALUE 4.7K
J 0
(8670 375);
DISPLAY 0.787234 (8670 375);
FORCEPROP 1 LAST MATERIAL CHIP
J 0
(8665 225);
DISPLAY 0.787234 (8665 225);
FORCEPROP 1 LAST TOLERANCE 1%
J 0
(8670 325);
DISPLAY 0.787234 (8670 325);
FORCEPROP 1 LAST $LOCATION R3296
J 0
(8670 425);
DISPLAY 0.978723 (8670 425);
FORCEPROP 1 LASTPIN (8625 400) $PN 1
J 0
(8630 362);
DISPLAY 0.787234 (8630 362);
PAINT MONO (8630 362);
FORCEPROP 1 LASTPIN (8625 200) $PN 2
J 0
(8630 210);
DISPLAY 0.787234 (8630 210);
PAINT MONO (8630 210);
FORCEPROP 1 LAST PATH I324
J 0
(8675 475);
DISPLAY 0.978723 (8675 475);
PAINT WHITE (8675 475);
DISPLAY INVISIBLE (8675 475);
FORCEPROP 2 LAST CDS_LIB pure_quanta
J 0
(8625 300);
DISPLAY INVISIBLE (8625 300);
FORCEPROP 0 LAST CDS_LOCATION R3296
J 0
(8675 475);
DISPLAY 1.021277 (8675 475);
DISPLAY INVISIBLE (8675 475);
FORCEPROP 0 LAST $SEC 1
J 0
(8675 475);
DISPLAY 0.680851 (8675 475);
PAINT MONO (8675 475);
DISPLAY INVISIBLE (8675 475);
FORCEPROP 0 LAST CDS_SEC 1
J 0
(8675 475);
DISPLAY 1.021277 (8675 475);
DISPLAY INVISIBLE (8675 475);
FORCEADD UNIVERSAL_POWER..1
(8050 -200);
FORCEPROP 3 LASTPIN (8050 -250) SIG_NAME P3V3_AUX\g
J 0
(8060 -240);
DISPLAY 0.659574 (8060 -240);
PAINT MONO (8060 -240);
DISPLAY INVISIBLE (8060 -240);
FORCEPROP 1 LAST HDL_POWER P3V3_AUX
J 1
(8050 -150);
DISPLAY 0.723404 (8050 -150);
PAINT GREEN (8050 -150);
FORCEPROP 1 LAST PATH I325
J 0
(8100 -175);
DISPLAY 0.872340 (8100 -175);
PAINT AQUA (8100 -175);
DISPLAY INVISIBLE (8100 -175);
FORCEPROP 2 LAST CDS_LIB logical_power
J 0
(8050 -200);
DISPLAY INVISIBLE (8050 -200);
FORCEADD Q_CAP..1
(8050 -750);
FORCEPROP 1 LAST PART_NUMBER CH5104KEB02
J 0
(8100 -950);
DISPLAY 0.510638 (8100 -950);
DISPLAY INVISIBLE (8100 -950);
FORCEPROP 1 LAST PACK_TYPE C0402
J 0
(8100 -900);
DISPLAY 0.638298 (8100 -900);
FORCEPROP 1 LAST MATERIAL X6S
J 0
(8100 -850);
DISPLAY 0.638298 (8100 -850);
FORCEPROP 1 LAST VALUE 1UF
J 0
(8100 -700);
DISPLAY 0.638298 (8100 -700);
FORCEPROP 1 LAST TOLERANCE 10%
J 0
(8100 -800);
DISPLAY 0.638298 (8100 -800);
FORCEPROP 1 LAST VOLTAGE 25V
J 0
(8100 -750);
DISPLAY 0.638298 (8100 -750);
FORCEPROP 1 LAST $LOCATION C2007
J 0
(8100 -650);
DISPLAY 0.978723 (8100 -650);
FORCEPROP 1 LASTPIN (8050 -650) $PN 1
J 0
(8060 -670);
DISPLAY 0.787234 (8060 -670);
PAINT MONO (8060 -670);
FORCEPROP 1 LASTPIN (8050 -850) $PN 2
J 0
(8060 -870);
DISPLAY 0.787234 (8060 -870);
PAINT MONO (8060 -870);
FORCEPROP 2 LAST CDS_LIB pure_quanta
J 0
(8050 -750);
DISPLAY INVISIBLE (8050 -750);
FORCEPROP 2 LAST BOM_COST VR_SYSTEM 
J 0
(8100 -600);
DISPLAY 0.680851 (8100 -600);
DISPLAY INVISIBLE (8100 -600);
FORCEPROP 1 LAST PATH I326
J 0
(8100 -600);
DISPLAY 0.978723 (8100 -600);
PAINT WHITE (8100 -600);
DISPLAY INVISIBLE (8100 -600);
FORCEPROP 0 LAST CDS_LOCATION C2007
J 0
(8100 -600);
DISPLAY 1.021277 (8100 -600);
DISPLAY INVISIBLE (8100 -600);
FORCEPROP 0 LAST $SEC 1
J 0
(8100 -600);
DISPLAY 0.680851 (8100 -600);
PAINT MONO (8100 -600);
DISPLAY INVISIBLE (8100 -600);
FORCEPROP 0 LAST CDS_SEC 1
J 0
(8100 -600);
DISPLAY 1.021277 (8100 -600);
DISPLAY INVISIBLE (8100 -600);
FORCEADD SN74LVC2G07DCKR..1
(7675 -400);
FORCEPROP 1 LAST PART_NUMBER AL002G07006
J 0
(7500 -240);
DISPLAY 0.723404 (7500 -240);
PAINT GREEN (7500 -240);
DISPLAY INVISIBLE (7500 -240);
FORCEPROP 2 LAST PACK_TYPE SMLF
J 0
(7500 -150);
DISPLAY 1.021277 (7500 -150);
FORCEPROP 1 LAST MATERIAL IC
J 0
(7500 -290);
DISPLAY 0.723404 (7500 -290);
PAINT GREEN (7500 -290);
FORCEPROP 2 LAST VALUE SN74LVC2G07DCKR
J 0
(7500 -100);
DISPLAY 1.021277 (7500 -100);
FORCEPROP 1 LAST $LOCATION U259
J 0
(7500 -195);
DISPLAY 0.723404 (7500 -195);
PAINT GREEN (7500 -195);
FORCEPROP 0 LASTPIN (7350 -350) $PN 1
J 2
(7340 -340);
DISPLAY 0.680851 (7340 -340);
PAINT MONO (7340 -340);
FORCEPROP 0 LASTPIN (8000 -350) $PN 6
J 0
(8010 -340);
DISPLAY 0.680851 (8010 -340);
PAINT MONO (8010 -340);
FORCEPROP 0 LASTPIN (7350 -450) $PN 3
J 2
(7340 -440);
DISPLAY 0.680851 (7340 -440);
PAINT MONO (7340 -440);
FORCEPROP 0 LASTPIN (8000 -450) $PN 4
J 0
(8010 -440);
DISPLAY 0.680851 (8010 -440);
PAINT MONO (8010 -440);
FORCEPROP 0 LASTPIN (7350 -400) $PN 2
J 2
(7340 -390);
DISPLAY 0.680851 (7340 -390);
PAINT MONO (7340 -390);
FORCEPROP 0 LASTPIN (8000 -400) $PN 5
J 0
(8010 -390);
DISPLAY 0.680851 (8010 -390);
PAINT MONO (8010 -390);
FORCEPROP 1 LAST PATH I327
J 0
(7825 -295);
DISPLAY 0.723404 (7825 -295);
PAINT GREEN (7825 -295);
DISPLAY INVISIBLE (7825 -295);
FORCEPROP 2 LAST CDS_LIB pure_quanta
J 0
(7675 -400);
DISPLAY INVISIBLE (7675 -400);
FORCEPROP 1 LAST NEEDS_NO_SIZE TRUE
J 0
(7675 -400);
DISPLAY 0.468085 (7675 -400);
PAINT GREEN (7675 -400);
DISPLAY INVISIBLE (7675 -400);
FORCEPROP 0 LAST CDS_LOCATION U259
J 0
(7500 -50);
DISPLAY 1.021277 (7500 -50);
DISPLAY INVISIBLE (7500 -50);
FORCEPROP 0 LAST $SEC 1
J 0
(7500 -50);
DISPLAY 0.680851 (7500 -50);
PAINT MONO (7500 -50);
DISPLAY INVISIBLE (7500 -50);
FORCEPROP 0 LAST CDS_SEC 1
J 0
(7500 -50);
DISPLAY 1.021277 (7500 -50);
DISPLAY INVISIBLE (7500 -50);
FORCEADD UNIVERSAL_GND..1
(7250 -600);
FORCEPROP 3 LASTPIN (7250 -550) SIG_NAME GND\g
J 0
(7260 -540);
DISPLAY 0.659574 (7260 -540);
PAINT MONO (7260 -540);
DISPLAY INVISIBLE (7260 -540);
FORCEPROP 1 LAST PATH I328
J 0
(7325 -600);
DISPLAY 0.872340 (7325 -600);
PAINT AQUA (7325 -600);
DISPLAY INVISIBLE (7325 -600);
FORCEPROP 1 LAST HDL_POWER GND
J 1
(7275 -675);
DISPLAY 0.872340 (7275 -675);
PAINT GREEN (7275 -675);
DISPLAY INVISIBLE (7275 -675);
FORCEPROP 2 LAST CDS_LIB logical_power
J 0
(7250 -600);
DISPLAY INVISIBLE (7250 -600);
FORCEADD OFFPAGE..1
(6150 -350);
FORCEPROP 2 LASTPIN (6200 -350) SIG_NAME M2_SSD0_CLKREQ_EN_N
J 0
(6240 -340);
DISPLAY 0.808511 (6240 -340);
PAINT WHITE (6240 -340);
FORCEPROP 2 LAST $XR1 183 
J 0
(5748 -350);
DISPLAY 0.638298 (5748 -350);
PAINT MONO (5748 -350);
FORCEPROP 2 LAST $XR0 190 
J 0
(5868 -350);
DISPLAY 0.638298 (5868 -350);
PAINT MONO (5868 -350);
FORCEPROP 1 LAST COMMENT_BODY TRUE
J 0
(6275 -450);
DISPLAY 0.872340 (6275 -450);
PAINT GREEN (6275 -450);
DISPLAY INVISIBLE (6275 -450);
FORCEPROP 1 LAST OFFPAGE TRUE
J 0
(6475 -475);
DISPLAY 0.872340 (6475 -475);
PAINT AQUA (6475 -475);
DISPLAY INVISIBLE (6475 -475);
FORCEPROP 2 LAST CDS_LIB standard
J 0
(6150 -350);
DISPLAY INVISIBLE (6150 -350);
FORCEPROP 2 LAST PATH I329
J 0
(5900 -300);
DISPLAY 1.021277 (5900 -300);
DISPLAY INVISIBLE (5900 -300);
FORCEADD OFFPAGE..2
(12525 -450);
FORCEPROP 2 LAST $XR0 190 
J 0
(12714 -450);
DISPLAY 0.638298 (12714 -450);
PAINT MONO (12714 -450);
FORCEPROP 2 LAST PATH I336
J 0
(12725 -400);
DISPLAY 1.021277 (12725 -400);
DISPLAY INVISIBLE (12725 -400);
FORCEPROP 1 LAST COMMENT_BODY TRUE
J 0
(12480 -545);
DISPLAY 0.872340 (12480 -545);
PAINT GREEN (12480 -545);
DISPLAY INVISIBLE (12480 -545);
FORCEPROP 1 LAST OFFPAGE TRUE
J 0
(12850 -575);
DISPLAY 0.872340 (12850 -575);
PAINT GREEN (12850 -575);
DISPLAY INVISIBLE (12850 -575);
FORCEPROP 2 LAST CDS_LIB standard
J 0
(12525 -450);
PAINT MONO (12525 -450);
DISPLAY INVISIBLE (12525 -450);
FORCEADD Q_RES..2
(10725 -250);
FORCEPROP 1 LAST PART_NUMBER CS24702JB10
J 0
(10765 -375);
DISPLAY 0.638298 (10765 -375);
DISPLAY INVISIBLE (10765 -375);
FORCEPROP 1 LAST MATERIAL CHIP
J 0
(10765 -325);
DISPLAY 0.638298 (10765 -325);
FORCEPROP 1 LAST VALUE 4.7K
J 0
(10770 -175);
DISPLAY 0.638298 (10770 -175);
FORCEPROP 1 LAST TOLERANCE 5%
J 0
(10770 -225);
DISPLAY 0.638298 (10770 -225);
FORCEPROP 1 LAST WATTAGE 1/16W
J 0
(10765 -275);
DISPLAY 0.638298 (10765 -275);
FORCEPROP 1 LAST PACK_TYPE 0402LF
J 0
(10775 -375);
DISPLAY 0.638298 (10775 -375);
FORCEPROP 1 LAST $LOCATION R2121
J 0
(10770 -125);
DISPLAY 0.638298 (10770 -125);
FORCEPROP 1 LASTPIN (10725 -150) $PN 1
J 0
(10730 -188);
DISPLAY 0.787234 (10730 -188);
PAINT MONO (10730 -188);
FORCEPROP 1 LASTPIN (10725 -350) $PN 2
J 0
(10730 -340);
DISPLAY 0.787234 (10730 -340);
PAINT MONO (10730 -340);
FORCEPROP 2 LAST CDS_LIB pure_quanta
J 0
(10725 -250);
DISPLAY INVISIBLE (10725 -250);
FORCEPROP 1 LAST PATH I337
J 0
(10775 -75);
DISPLAY 0.978723 (10775 -75);
PAINT WHITE (10775 -75);
DISPLAY INVISIBLE (10775 -75);
FORCEPROP 0 LAST CDS_LOCATION R2121
J 0
(10775 -75);
DISPLAY 1.021277 (10775 -75);
DISPLAY INVISIBLE (10775 -75);
FORCEPROP 0 LAST $SEC 1
J 0
(10775 -75);
DISPLAY 0.680851 (10775 -75);
PAINT MONO (10775 -75);
DISPLAY INVISIBLE (10775 -75);
FORCEPROP 0 LAST CDS_SEC 1
J 0
(10775 -75);
DISPLAY 1.021277 (10775 -75);
DISPLAY INVISIBLE (10775 -75);
FORCEADD UNIVERSAL_POWER..1
(10725 -25);
FORCEPROP 3 LASTPIN (10725 -75) SIG_NAME P3V3_AUX\g
J 0
(10735 -65);
DISPLAY 0.659574 (10735 -65);
PAINT MONO (10735 -65);
DISPLAY INVISIBLE (10735 -65);
FORCEPROP 1 LAST HDL_POWER P3V3_AUX
J 1
(10725 25);
DISPLAY 0.872340 (10725 25);
PAINT GREEN (10725 25);
FORCEPROP 2 LAST CDS_LIB logical_power
J 0
(10725 -25);
DISPLAY INVISIBLE (10725 -25);
FORCEPROP 1 LAST PATH I338
J 0
(10775 0);
DISPLAY 0.872340 (10775 0);
PAINT AQUA (10775 0);
DISPLAY INVISIBLE (10775 0);
FORCEADD OFFPAGE..1
(6150 -450);
FORCEPROP 2 LAST $XR0 215 
J 0
(5868 -450);
DISPLAY 0.638298 (5868 -450);
PAINT MONO (5868 -450);
FORCEPROP 2 LAST PATH I340
J 0
(6200 -375);
DISPLAY 1.021277 (6200 -375);
DISPLAY INVISIBLE (6200 -375);
FORCEPROP 1 LAST OFFPAGE TRUE
J 0
(6475 -575);
DISPLAY 0.872340 (6475 -575);
PAINT AQUA (6475 -575);
DISPLAY INVISIBLE (6475 -575);
FORCEPROP 1 LAST COMMENT_BODY TRUE
J 0
(6275 -550);
DISPLAY 0.872340 (6275 -550);
PAINT GREEN (6275 -550);
DISPLAY INVISIBLE (6275 -550);
FORCEPROP 2 LAST CDS_LIB standard
J 0
(6150 -450);
DISPLAY INVISIBLE (6150 -450);
FORCEADD UNIVERSAL_POWER..1
(7650 1775);
FORCEPROP 3 LASTPIN (7650 1725) SIG_NAME P3V3_M2_0\g
J 0
(7660 1735);
DISPLAY 0.659574 (7660 1735);
PAINT MONO (7660 1735);
DISPLAY INVISIBLE (7660 1735);
FORCEPROP 1 LAST HDL_POWER P3V3_M2_0
J 1
(7650 1825);
DISPLAY 0.872340 (7650 1825);
PAINT GREEN (7650 1825);
FORCEPROP 1 LAST PATH I341
J 0
(7700 1800);
DISPLAY 0.872340 (7700 1800);
PAINT AQUA (7700 1800);
DISPLAY INVISIBLE (7700 1800);
FORCEPROP 2 LAST CDS_LIB logical_power
J 0
(7650 1775);
DISPLAY INVISIBLE (7650 1775);
FORCEADD MOSFET_NCH_DUAL..1
(9800 -50);
FORCEPROP 1 LAST PART_NUMBER BAM138K0003
J 0
(9951 -136);
DISPLAY 0.723404 (9951 -136);
PAINT GREEN (9951 -136);
DISPLAY INVISIBLE (9951 -136);
FORCEPROP 1 LAST MATERIAL IC
J 0
(9951 -201);
DISPLAY 0.723404 (9951 -201);
PAINT GREEN (9951 -201);
FORCEPROP 2 LAST VALUE PJT138K
J 0
(9975 -25);
DISPLAY 1.021277 (9975 -25);
FORCEPROP 2 LAST PART_TYPE SMLF
J 0
(9975 25);
DISPLAY 1.021277 (9975 25);
FORCEPROP 1 LAST LOCATION Q95
J 0
(9951 -76);
DISPLAY 0.723404 (9951 -76);
PAINT GREEN (9951 -76);
FORCEPROP 0 LASTPIN (9850 150) $PN 6
R 1
J 0
(9840 160);
DISPLAY 0.680851 (9840 160);
PAINT MONO (9840 160);
FORCEPROP 0 LASTPIN (9600 -100) $PN 2
J 2
(9590 -90);
DISPLAY 0.680851 (9590 -90);
PAINT MONO (9590 -90);
FORCEPROP 0 LASTPIN (9850 -250) $PN 1
R 1
J 2
(9840 -260);
DISPLAY 0.680851 (9840 -260);
PAINT MONO (9840 -260);
FORCEPROP 1 LAST NEEDS_NO_SIZE TRUE
J 0
(9800 -51);
DISPLAY 0.468085 (9800 -51);
PAINT GREEN (9800 -51);
DISPLAY INVISIBLE (9800 -51);
FORCEPROP 1 LAST CDS_LMAN_SYM_OUTLINE -150,150,150,-150
J 0
(9800 -50);
DISPLAY 0.468085 (9800 -50);
PAINT GREEN (9800 -50);
DISPLAY INVISIBLE (9800 -50);
FORCEPROP 1 LAST PATH I342
J 0
(9800 -50);
DISPLAY 0.723404 (9800 -50);
PAINT GREEN (9800 -50);
DISPLAY INVISIBLE (9800 -50);
FORCEPROP 2 LAST CDS_LIB pure_quanta
J 0
(9800 -50);
DISPLAY INVISIBLE (9800 -50);
FORCEPROP 0 LAST $SEC 1
J 0
(9975 75);
DISPLAY 0.680851 (9975 75);
PAINT MONO (9975 75);
DISPLAY INVISIBLE (9975 75);
FORCEPROP 0 LAST CDS_SEC 1
J 0
(9975 75);
DISPLAY 1.021277 (9975 75);
DISPLAY INVISIBLE (9975 75);
FORCEADD MOSFET_NCH_DUAL..2
(10100 -775);
FORCEPROP 1 LAST PART_NUMBER BAM138K0003
J 0
(10251 -869);
DISPLAY 0.723404 (10251 -869);
PAINT GREEN (10251 -869);
DISPLAY INVISIBLE (10251 -869);
FORCEPROP 2 LAST PART_TYPE SMLF
J 0
(10275 -700);
DISPLAY 1.021277 (10275 -700);
FORCEPROP 2 LAST VALUE PJT138K
J 0
(10275 -750);
DISPLAY 1.021277 (10275 -750);
FORCEPROP 1 LAST MATERIAL IC
J 0
(10251 -924);
DISPLAY 0.723404 (10251 -924);
PAINT GREEN (10251 -924);
FORCEPROP 1 LAST LOCATION Q95
J 0
(10251 -799);
DISPLAY 0.723404 (10251 -799);
PAINT GREEN (10251 -799);
FORCEPROP 0 LASTPIN (10150 -575) $PN 3
R 1
J 0
(10140 -565);
DISPLAY 0.680851 (10140 -565);
PAINT MONO (10140 -565);
FORCEPROP 0 LASTPIN (9900 -825) $PN 5
J 2
(9890 -815);
DISPLAY 0.680851 (9890 -815);
PAINT MONO (9890 -815);
FORCEPROP 0 LASTPIN (10150 -975) $PN 4
R 1
J 2
(10140 -985);
DISPLAY 0.680851 (10140 -985);
PAINT MONO (10140 -985);
FORCEPROP 1 LAST PATH I343
J 0
(10250 -925);
DISPLAY 0.723404 (10250 -925);
PAINT GREEN (10250 -925);
DISPLAY INVISIBLE (10250 -925);
FORCEPROP 2 LAST CDS_LIB pure_quanta
J 0
(10100 -775);
DISPLAY INVISIBLE (10100 -775);
FORCEPROP 1 LAST CDS_LMAN_SYM_OUTLINE -150,150,150,-150
J 0
(10100 -775);
DISPLAY 0.468085 (10100 -775);
PAINT GREEN (10100 -775);
DISPLAY INVISIBLE (10100 -775);
FORCEPROP 1 LAST NEEDS_NO_SIZE TRUE
J 0
(10250 -884);
DISPLAY 0.468085 (10250 -884);
PAINT GREEN (10250 -884);
DISPLAY INVISIBLE (10250 -884);
FORCEPROP 0 LAST $SEC 2
J 0
(10275 -650);
DISPLAY 0.680851 (10275 -650);
PAINT MONO (10275 -650);
DISPLAY INVISIBLE (10275 -650);
FORCEPROP 0 LAST CDS_SEC 2
J 0
(10275 -650);
DISPLAY 1.021277 (10275 -650);
DISPLAY INVISIBLE (10275 -650);
FORCEADD Q_RES..1
(11150 -450);
FORCEPROP 1 LAST PART_NUMBER CS03322FB03
J 0
(11025 -500);
DISPLAY 0.510638 (11025 -500);
DISPLAY INVISIBLE (11025 -500);
FORCEPROP 1 LAST TOLERANCE 1%
J 0
(11375 -450);
DISPLAY 0.510638 (11375 -450);
FORCEPROP 1 LAST VALUE 33.2
J 2
(11350 -450);
DISPLAY 0.510638 (11350 -450);
FORCEPROP 1 LAST MATERIAL CHIP
J 0
(11450 -450);
DISPLAY 0.510638 (11450 -450);
FORCEPROP 1 LAST LOCATION R2113
J 0
(10975 -450);
DISPLAY 0.510638 (10975 -450);
FORCEPROP 1 LASTPIN (11050 -450) $PN 1
J 0
(11062 -438);
DISPLAY 0.787234 (11062 -438);
PAINT MONO (11062 -438);
FORCEPROP 1 LASTPIN (11250 -450) $PN 2
J 0
(11212 -438);
DISPLAY 0.787234 (11212 -438);
PAINT MONO (11212 -438);
FORCEPROP 2 LAST CDS_LIB pure_quanta
J 0
(11150 -450);
DISPLAY INVISIBLE (11150 -450);
FORCEPROP 1 LAST PATH I344
J 0
(11100 -300);
DISPLAY 0.978723 (11100 -300);
PAINT WHITE (11100 -300);
DISPLAY INVISIBLE (11100 -300);
FORCEPROP 1 LAST PACK_TYPE 0402LF
J 0
(11025 -325);
DISPLAY 0.510638 (11025 -325);
DISPLAY INVISIBLE (11025 -325);
FORCEPROP 1 LAST WATTAGE 1/16W
J 2
(11325 -325);
DISPLAY 0.510638 (11325 -325);
DISPLAY INVISIBLE (11325 -325);
FORCEPROP 0 LAST $SEC 1
J 0
(11450 -425);
DISPLAY 0.680851 (11450 -425);
PAINT MONO (11450 -425);
DISPLAY INVISIBLE (11450 -425);
FORCEPROP 0 LAST CDS_SEC 1
J 0
(11450 -425);
DISPLAY 1.021277 (11450 -425);
DISPLAY INVISIBLE (11450 -425);
FORCEADD Q_CAP..1
(11275 4275);
FORCEPROP 1 LAST PART_NUMBER CH6221ME900
J 0
(11325 4125);
DISPLAY 0.638298 (11325 4125);
DISPLAY INVISIBLE (11325 4125);
FORCEPROP 1 LAST PACK_TYPE C0603
J 0
(11325 4075);
DISPLAY 0.638298 (11325 4075);
FORCEPROP 1 LAST MATERIAL X6S
J 0
(11325 4175);
DISPLAY 0.638298 (11325 4175);
FORCEPROP 1 LAST TOLERANCE 20%
J 0
(11325 4225);
DISPLAY 0.638298 (11325 4225);
FORCEPROP 1 LAST VALUE 22UF
J 0
(11325 4325);
DISPLAY 0.638298 (11325 4325);
FORCEPROP 1 LAST VOLTAGE 6.3V
J 0
(11325 4275);
DISPLAY 0.638298 (11325 4275);
FORCEPROP 1 LAST LOCATION C1920
J 0
(11325 4375);
DISPLAY 0.978723 (11325 4375);
FORCEPROP 1 LASTPIN (11275 4375) $PN 1
J 0
(11285 4355);
DISPLAY 0.787234 (11285 4355);
FORCEPROP 1 LASTPIN (11275 4175) $PN 2
J 0
(11285 4155);
DISPLAY 0.787234 (11285 4155);
FORCEPROP 2 LAST CDS_LIB pure_quanta
J 0
(11275 4275);
PAINT MONO (11275 4275);
DISPLAY INVISIBLE (11275 4275);
FORCEPROP 1 LAST PATH I88
J 0
(11325 4425);
DISPLAY 0.978723 (11325 4425);
PAINT WHITE (11325 4425);
DISPLAY INVISIBLE (11325 4425);
FORCEPROP 2 LAST $SEC 1
J 0
(11325 4475);
DISPLAY 0.680851 (11325 4475);
PAINT MONO (11325 4475);
DISPLAY INVISIBLE (11325 4475);
FORCEPROP 2 LAST CDS_SEC 1
J 0
(11325 4475);
DISPLAY 1.021277 (11325 4475);
DISPLAY INVISIBLE (11325 4475);
FORCEADD UNIVERSAL_POWER..1
(11275 4650);
FORCEPROP 3 LASTPIN (11275 4600) SIG_NAME P3V3_M2_0\g
J 0
(11285 4610);
DISPLAY 0.659574 (11285 4610);
PAINT MONO (11285 4610);
DISPLAY INVISIBLE (11285 4610);
FORCEPROP 1 LAST HDL_POWER P3V3_M2_0
J 1
(11275 4700);
DISPLAY 0.872340 (11275 4700);
PAINT GREEN (11275 4700);
FORCEPROP 2 LAST CDS_LIB logical_power
J 0
(11275 4650);
PAINT MONO (11275 4650);
DISPLAY INVISIBLE (11275 4650);
FORCEPROP 1 LAST PATH I89
J 0
(11325 4675);
DISPLAY 0.872340 (11325 4675);
PAINT AQUA (11325 4675);
DISPLAY INVISIBLE (11325 4675);
FORCEADD Q_CAP..1
(11675 4275);
FORCEPROP 1 LAST PART_NUMBER CH6221ME900
J 0
(11725 4125);
DISPLAY 0.638298 (11725 4125);
DISPLAY INVISIBLE (11725 4125);
FORCEPROP 1 LAST VALUE 22UF
J 0
(11725 4325);
DISPLAY 0.638298 (11725 4325);
FORCEPROP 1 LAST VOLTAGE 6.3V
J 0
(11725 4275);
DISPLAY 0.638298 (11725 4275);
FORCEPROP 1 LAST PACK_TYPE C0603
J 0
(11725 4075);
DISPLAY 0.638298 (11725 4075);
FORCEPROP 1 LAST MATERIAL X6S
J 0
(11725 4175);
DISPLAY 0.638298 (11725 4175);
FORCEPROP 1 LAST TOLERANCE 20%
J 0
(11725 4225);
DISPLAY 0.638298 (11725 4225);
FORCEPROP 1 LAST LOCATION C1921
J 0
(11725 4375);
DISPLAY 0.978723 (11725 4375);
FORCEPROP 1 LASTPIN (11675 4375) $PN 1
J 0
(11685 4355);
DISPLAY 0.787234 (11685 4355);
FORCEPROP 1 LASTPIN (11675 4175) $PN 2
J 0
(11685 4155);
DISPLAY 0.787234 (11685 4155);
FORCEPROP 2 LAST CDS_LIB pure_quanta
J 0
(11675 4275);
PAINT MONO (11675 4275);
DISPLAY INVISIBLE (11675 4275);
FORCEPROP 1 LAST PATH I90
J 0
(11725 4425);
DISPLAY 0.978723 (11725 4425);
PAINT WHITE (11725 4425);
DISPLAY INVISIBLE (11725 4425);
FORCEPROP 2 LAST $SEC 1
J 0
(11725 4475);
DISPLAY 0.680851 (11725 4475);
PAINT MONO (11725 4475);
DISPLAY INVISIBLE (11725 4475);
FORCEPROP 2 LAST CDS_SEC 1
J 0
(11725 4475);
DISPLAY 1.021277 (11725 4475);
DISPLAY INVISIBLE (11725 4475);
FORCEADD Q_CAP..1
(12075 4275);
FORCEPROP 1 LAST PART_NUMBER CH6221ME900
J 0
(12125 4125);
DISPLAY 0.638298 (12125 4125);
DISPLAY INVISIBLE (12125 4125);
FORCEPROP 1 LAST MATERIAL X6S
J 0
(12125 4175);
DISPLAY 0.638298 (12125 4175);
FORCEPROP 1 LAST PACK_TYPE C0603
J 0
(12125 4075);
DISPLAY 0.638298 (12125 4075);
FORCEPROP 1 LAST VOLTAGE 6.3V
J 0
(12125 4275);
DISPLAY 0.638298 (12125 4275);
FORCEPROP 1 LAST TOLERANCE 20%
J 0
(12125 4225);
DISPLAY 0.638298 (12125 4225);
FORCEPROP 1 LAST VALUE 22UF
J 0
(12125 4325);
DISPLAY 0.638298 (12125 4325);
FORCEPROP 1 LAST LOCATION C1922
J 0
(12125 4375);
DISPLAY 0.978723 (12125 4375);
FORCEPROP 1 LASTPIN (12075 4375) $PN 1
J 0
(12085 4355);
DISPLAY 0.787234 (12085 4355);
FORCEPROP 1 LASTPIN (12075 4175) $PN 2
J 0
(12085 4155);
DISPLAY 0.787234 (12085 4155);
FORCEPROP 2 LAST CDS_LIB pure_quanta
J 0
(12075 4275);
PAINT MONO (12075 4275);
DISPLAY INVISIBLE (12075 4275);
FORCEPROP 1 LAST PATH I96
J 0
(12125 4425);
DISPLAY 0.978723 (12125 4425);
PAINT WHITE (12125 4425);
DISPLAY INVISIBLE (12125 4425);
FORCEPROP 2 LAST $SEC 1
J 0
(12125 4475);
DISPLAY 0.680851 (12125 4475);
PAINT MONO (12125 4475);
DISPLAY INVISIBLE (12125 4475);
FORCEPROP 2 LAST CDS_SEC 1
J 0
(12125 4475);
DISPLAY 1.021277 (12125 4475);
DISPLAY INVISIBLE (12125 4475);
FORCEADD Q_CAP..1
(12475 4275);
FORCEPROP 1 LAST PART_NUMBER CH4104K1B00
J 0
(12525 4125);
DISPLAY 0.638298 (12525 4125);
DISPLAY INVISIBLE (12525 4125);
FORCEPROP 1 LAST PACK_TYPE 0402
J 0
(12525 4075);
DISPLAY 0.638298 (12525 4075);
FORCEPROP 1 LAST TOLERANCE 10%
J 0
(12525 4225);
DISPLAY 0.638298 (12525 4225);
FORCEPROP 1 LAST MATERIAL X7R
J 0
(12525 4175);
DISPLAY 0.638298 (12525 4175);
FORCEPROP 1 LAST VALUE 0.1UF
J 0
(12525 4325);
DISPLAY 0.638298 (12525 4325);
FORCEPROP 1 LAST VOLTAGE 25V
J 0
(12525 4275);
DISPLAY 0.638298 (12525 4275);
FORCEPROP 1 LAST LOCATION C1923
J 0
(12525 4375);
DISPLAY 0.978723 (12525 4375);
FORCEPROP 1 LASTPIN (12475 4375) $PN 1
J 0
(12485 4355);
DISPLAY 0.787234 (12485 4355);
FORCEPROP 1 LASTPIN (12475 4175) $PN 2
J 0
(12485 4155);
DISPLAY 0.787234 (12485 4155);
FORCEPROP 2 LAST CDS_LIB pure_quanta
J 0
(12475 4275);
PAINT MONO (12475 4275);
DISPLAY INVISIBLE (12475 4275);
FORCEPROP 1 LAST PATH I97
J 0
(12525 4425);
DISPLAY 0.978723 (12525 4425);
PAINT WHITE (12525 4425);
DISPLAY INVISIBLE (12525 4425);
FORCEPROP 2 LAST $SEC 1
J 0
(12525 4475);
DISPLAY 0.680851 (12525 4475);
PAINT MONO (12525 4475);
DISPLAY INVISIBLE (12525 4475);
FORCEPROP 2 LAST CDS_SEC 1
J 0
(12525 4475);
DISPLAY 1.021277 (12525 4475);
DISPLAY INVISIBLE (12525 4475);
FORCEADD Q_CAP..1
(12875 4275);
FORCEPROP 1 LAST PART_NUMBER CH4104K1B00
J 0
(12925 4125);
DISPLAY 0.638298 (12925 4125);
DISPLAY INVISIBLE (12925 4125);
FORCEPROP 1 LAST TOLERANCE 10%
J 0
(12925 4225);
DISPLAY 0.638298 (12925 4225);
FORCEPROP 1 LAST VOLTAGE 25V
J 0
(12925 4275);
DISPLAY 0.638298 (12925 4275);
FORCEPROP 1 LAST MATERIAL X7R
J 0
(12925 4175);
DISPLAY 0.638298 (12925 4175);
FORCEPROP 1 LAST VALUE 0.1UF
J 0
(12925 4325);
DISPLAY 0.638298 (12925 4325);
FORCEPROP 1 LAST PACK_TYPE 0402
J 0
(12925 4075);
DISPLAY 0.638298 (12925 4075);
FORCEPROP 1 LAST LOCATION C1924
J 0
(12925 4375);
DISPLAY 0.978723 (12925 4375);
FORCEPROP 1 LASTPIN (12875 4375) $PN 1
J 0
(12885 4355);
DISPLAY 0.787234 (12885 4355);
FORCEPROP 1 LASTPIN (12875 4175) $PN 2
J 0
(12885 4155);
DISPLAY 0.787234 (12885 4155);
FORCEPROP 2 LAST CDS_LIB pure_quanta
J 0
(12875 4275);
PAINT MONO (12875 4275);
DISPLAY INVISIBLE (12875 4275);
FORCEPROP 1 LAST PATH I98
J 0
(12925 4425);
DISPLAY 0.978723 (12925 4425);
PAINT WHITE (12925 4425);
DISPLAY INVISIBLE (12925 4425);
FORCEPROP 2 LAST $SEC 1
J 0
(12925 4475);
DISPLAY 0.680851 (12925 4475);
PAINT MONO (12925 4475);
DISPLAY INVISIBLE (12925 4475);
FORCEPROP 2 LAST CDS_SEC 1
J 0
(12925 4475);
DISPLAY 1.021277 (12925 4475);
DISPLAY INVISIBLE (12925 4475);
FORCEADD UNIVERSAL_GND..1
(13275 3925);
FORCEPROP 3 LASTPIN (13275 3975) SIG_NAME GND\g
J 0
(13285 3985);
DISPLAY 0.659574 (13285 3985);
PAINT MONO (13285 3985);
DISPLAY INVISIBLE (13285 3985);
FORCEPROP 2 LAST CATEGORY LED
J 0
(13175 4000);
DISPLAY INVISIBLE (13175 4000);
FORCEPROP 1 LAST HDL_POWER GND
J 1
(13300 3850);
DISPLAY 0.872340 (13300 3850);
PAINT GREEN (13300 3850);
DISPLAY INVISIBLE (13300 3850);
FORCEPROP 2 LAST CDS_LIB logical_power
J 0
(13275 3925);
PAINT MONO (13275 3925);
DISPLAY INVISIBLE (13275 3925);
FORCEPROP 1 LAST PATH I99
J 0
(13350 3925);
DISPLAY 0.872340 (13350 3925);
PAINT AQUA (13350 3925);
DISPLAY INVISIBLE (13350 3925);
FORCEADD DNS..2
(8750 4425);
PAINT RED (8750 4425);
FORCEPROP 1 LAST COMMENT_BODY TRUE
J 0
(8750 4425);
DISPLAY INVISIBLE (8750 4425);
FORCEPROP 2 LAST CDS_LIB mstr_misc
J 0
(8750 4425);
DISPLAY INVISIBLE (8750 4425);
FORCEADD DNS..2
(5455 3070);
PAINT RED (5455 3070);
FORCEPROP 2 LAST CDS_LIB mstr_misc
J 0
(5455 3070);
PAINT MONO (5455 3070);
DISPLAY INVISIBLE (5455 3070);
FORCEPROP 1 LAST COMMENT_BODY TRUE
J 0
(5455 3070);
DISPLAY INVISIBLE (5455 3070);
FORCEADD DESIGN_NOTE..1
(5425 4225);
FORCEPROP 0 LAST S1 1.DP/DN SWAP TX[0:3]
J 0
(5225 4075);
DISPLAY 1.021277 (5225 4075);
PAINT SKYBLUE (5225 4075);
FORCEPROP 0 LAST S2 2.LANE REVERSAL
J 0
(5225 3975);
DISPLAY 1.021277 (5225 3975);
PAINT SKYBLUE (5225 3975);
FORCEPROP 2 LAST CDS_LIB logical_power
J 0
(5425 4225);
DISPLAY INVISIBLE (5425 4225);
FORCEPROP 1 LAST COMMENT_BODY TRUE
J 0
(5450 4325);
DISPLAY 0.978723 (5450 4325);
DISPLAY INVISIBLE (5450 4325);
FORCEADD BOM_NOTE..1
(11375 2825);
FORCEPROP 0 LAST S1 CHANGE CH4101KEE02 TO CH4101KEE01
J 0
(11225 2675);
DISPLAY 0.808511 (11225 2675);
PAINT SKYBLUE (11225 2675);
FORCEPROP 1 LAST COMMENT_BODY TRUE
J 0
(11400 2925);
DISPLAY 0.978723 (11400 2925);
DISPLAY INVISIBLE (11400 2925);
FORCEPROP 2 LAST CDS_LIB logical_power
J 0
(11375 2825);
DISPLAY INVISIBLE (11375 2825);
FORCEADD QUANTA_TITLE_BLOCK_C..1
(13950 -1375);
FORCEPROP 0 LAST CDS_CON_LAST_MODIFIED Fri Aug 25 14:03:03 2023
J 0
(12065 -1360);
PAINT MONO (12065 -1360);
DISPLAY INVISIBLE (12065 -1360);
FORCEPROP 2 LAST CUSTOM_TXT_CDS <XR_PAGE_TITLE>
J 0
(6060 3875);
DISPLAY 0.638298 (6060 3875);
PAINT PINK (6060 3875);
DISPLAY INVISIBLE (6060 3875);
FORCEPROP 2 LAST CUSTOM_TXT_CDS <CON_LAST_MODIFIED>
J 0
(12065 -1360);
DISPLAY 0.978723 (12065 -1360);
FORCEPROP 2 LAST CUSTOM_TXT_CDS <Q_PROJ>
J 0
(11568 -1273);
DISPLAY 1.212766 (11568 -1273);
FORCEPROP 2 LAST CUSTOM_TXT_CDS <Q_NUMBER>
J 0
(12547 -1272);
DISPLAY 1.212766 (12547 -1272);
FORCEPROP 2 LAST CUSTOM_TXT_CDS <NAME_2>
J 0
(10775 -1325);
FORCEPROP 2 LAST CUSTOM_TXT_CDS <Q_REV>
J 0
(13766 -1272);
DISPLAY 1.212766 (13766 -1272);
FORCEPROP 2 LAST CUSTOM_TXT_CDS 01
J 0
(13766 -1272);
DISPLAY 1.212766 (13766 -1272);
FORCEPROP 2 LAST CUSTOM_TXT_CDS 01
J 0
(13766 -1272);
DISPLAY 1.212766 (13766 -1272);
FORCEPROP 2 LAST CUSTOM_TXT_CDS 01
J 0
(13766 -1272);
DISPLAY 1.212766 (13766 -1272);
FORCEPROP 2 LAST CUSTOM_TXT_CDS 01
J 0
(13766 -1272);
DISPLAY 1.212766 (13766 -1272);
FORCEPROP 2 LAST CUSTOM_TXT_CDS <CON_PAGE_NUM> OF <CON_TOTAL_PAGES>
J 0
(13504 -1357);
DISPLAY 0.978723 (13504 -1357);
FORCEPROP 2 LAST CUSTOM_TXT_CDS <NAME_1>
J 0
(10775 -1200);
FORCEPROP 1 LAST Q_TITLE PCH - M.2 - 0 CONN
J 0
(4609 -1349);
DISPLAY 1.957447 (4609 -1349);
PAINT GREEN (4609 -1349);
FORCEPROP 1 LAST Q_DEPT 
J 1
(10187 -1326);
DISPLAY 1.957447 (10187 -1326);
PAINT GREEN (10187 -1326);
FORCEPROP 2 LAST CDS_XR_PAGE_TITLE CR-190 : @S9S_MB_2U_LIB.S9S_MB_2U(SCH_1):PAGE190
J 0
(6060 3875);
DISPLAY 0.638298 (6060 3875);
PAINT PINK (6060 3875);
DISPLAY INVISIBLE (6060 3875);
FORCEPROP 2 LAST CDS_LIB pure_quanta
J 0
(13950 -1375);
PAINT MONO (13950 -1375);
DISPLAY INVISIBLE (13950 -1375);
FORCEPROP 1 LAST CDS_LMAN_SYM_OUTLINE -9475,6775,100,-125
J 0
(13950 -1375);
DISPLAY 0.468085 (13950 -1375);
PAINT GREEN (13950 -1375);
DISPLAY INVISIBLE (13950 -1375);
FORCEPROP 2 LAST PAGE_BORDER TRUE
J 0
(6060 3875);
DISPLAY 0.638298 (6060 3875);
PAINT PINK (6060 3875);
DISPLAY INVISIBLE (6060 3875);
FORCEPROP 1 LAST COMMENT_BODY TRUE
J 0
(13962 -1388);
DISPLAY 0.978723 (13962 -1388);
PAINT GREEN (13962 -1388);
DISPLAY INVISIBLE (13962 -1388);
WIRE 17 -1 (6175 4425)(7350 4425);
FORCEPROP 2 LAST SIG_NAME P3E_PCH_M2_RX_DP<2:0>
J 0
(6365 4435);
DISPLAY 0.680851 (6365 4435);
PAINT WHITE (6365 4435);
WIRE 17 -1 (7525 4325)(7525 4575);
WIRE 17 -1 (7525 4325)(7525 4075);
WIRE 17 -1 (7525 4575)(6175 4575);
FORCEPROP 2 LAST SIG_NAME P3E_PCH_M2_TX_C_DN<2:0>
J 0
(6365 4585);
DISPLAY 0.680851 (6365 4585);
PAINT WHITE (6365 4585);
WIRE 17 -1 (7675 4275)(7675 4525);
WIRE 17 -1 (7675 4025)(7675 4275);
WIRE 17 -1 (6175 4525)(7675 4525);
FORCEPROP 2 LAST SIG_NAME P3E_PCH_M2_TX_C_DP<2:0>
J 0
(6365 4535);
DISPLAY 0.680851 (6365 4535);
PAINT WHITE (6365 4535);
WIRE 17 -1 (7525 3825)(7525 4075);
WIRE 17 -1 (7675 4025)(7675 3775);
WIRE 17 -1 (7350 3925)(7350 4175);
WIRE 17 -1 (7350 4175)(7350 4425);
WIRE 17 -1 (7200 4375)(7200 4125);
WIRE 17 -1 (7200 4375)(7200 4475);
WIRE 17 -1 (7200 4125)(7200 3875);
WIRE 17 -1 (7200 4475)(6175 4475);
FORCEPROP 2 LAST SIG_NAME P3E_PCH_M2_RX_DN<2:0>
J 0
(6365 4485);
DISPLAY 0.680851 (6365 4485);
PAINT WHITE (6365 4485);
WIRE 16 -1 (10725 -150)(10725 -75);
WIRE 16 -1 (8625 400)(8625 575);
WIRE 16 -1 (6975 4025)(6975 4100);
WIRE 16 -1 (11275 4600)(11275 4475);
WIRE 16 -1 (11175 3275)(11175 3300);
WIRE 16 -1 (10700 3275)(11175 3275);
WIRE 16 -1 (6975 2800)(6975 2875);
WIRE 16 -1 (8050 -400)(8050 -250);
WIRE 16 -1 (8000 -400)(8050 -400);
WIRE 16 -1 (8050 -650)(8050 -400);
WIRE 16 -1 (9475 4600)(9475 4400);
WIRE 16 -1 (7650 1625)(7650 1725);
WIRE 16 -1 (10725 650)(10725 600);
WIRE 16 -1 (9350 1725)(9350 1825);
WIRE 16 -1 (9350 1725)(9600 1725);
WIRE 16 -1 (9350 1425)(9350 1725);
WIRE 16 -1 (9850 -250)(9850 -350);
WIRE 16 -1 (8050 -1000)(8050 -850);
WIRE 16 -1 (10300 825)(10300 725);
WIRE 16 -1 (9600 1325)(9600 1425);
WIRE 16 -1 (9350 925)(9350 825);
WIRE 16 -1 (7250 -550)(7250 -400);
WIRE 16 -1 (13350 2700)(13350 2800);
WIRE 16 -1 (7975 2250)(7975 2150);
WIRE 16 -1 (7975 2300)(7975 2250);
WIRE 16 -1 (7975 2250)(8125 2250);
WIRE 16 -1 (13275 4025)(13275 3975);
WIRE 16 -1 (12875 4025)(13275 4025);
WIRE 16 -1 (13275 4175)(13275 4025);
WIRE 16 -1 (5450 2900)(5450 2975);
WIRE 16 -1 (8125 4350)(7300 4350);
WIRE 16 -1 (7450 4150)(8125 4150);
WIRE 16 -1 (7625 4050)(8125 4050);
WIRE 16 -1 (7775 4000)(8125 4000);
WIRE 16 -1 (9325 2450)(10125 2450);
FORCEPROP 2 LAST SIG_NAME NC_M2_0_NC1
J 0
(9515 2460);
DISPLAY 0.680851 (9515 2460);
PAINT WHITE (9515 2460);
WIRE 16 -1 (9325 2500)(10125 2500);
FORCEPROP 2 LAST SIG_NAME NC_M2_0_NC2
J 0
(9515 2510);
DISPLAY 0.680851 (9515 2510);
PAINT WHITE (9515 2510);
WIRE 16 -1 (9325 2650)(10125 2650);
FORCEPROP 2 LAST SIG_NAME NC_M2_0_NC5
J 0
(9515 2660);
DISPLAY 0.680851 (9515 2660);
PAINT WHITE (9515 2660);
WIRE 16 -1 (9325 2850)(10125 2850);
FORCEPROP 2 LAST SIG_NAME NC_M2_0_NC9
J 0
(9515 2860);
DISPLAY 0.680851 (9515 2860);
PAINT WHITE (9515 2860);
WIRE 16 -1 (9325 3100)(10125 3100);
FORCEPROP 2 LAST SIG_NAME NC_M2_0_NC14
J 0
(9515 3110);
DISPLAY 0.680851 (9515 3110);
PAINT WHITE (9515 3110);
WIRE 16 -1 (9325 3500)(10300 3500);
FORCEPROP 2 LAST SIG_NAME FM_M2_SSD_0_PEDET
J 0
(9515 3510);
DISPLAY 0.680851 (9515 3510);
PAINT WHITE (9515 3510);
WIRE 16 -1 (10300 3500)(10500 3500);
WIRE 16 -1 (10300 3275)(10300 3500);
WIRE 16 -1 (10300 3275)(10500 3275);
WIRE 16 -1 (10575 3600)(9325 3600);
FORCEPROP 2 LAST SIG_NAME LED_M2_SSD_0_ACT_N
J 0
(9515 3610);
DISPLAY 0.680851 (9515 3610);
PAINT WHITE (9515 3610);
WIRE 16 -1 (9600 1725)(9600 1625);
WIRE 16 -1 (7075 3650)(8125 3650);
FORCEPROP 0 LAST CDS_PHYS_NET_NAME NC_M2_1_SUSCLK
J 0
(7265 3692);
PAINT MONO (7265 3692);
DISPLAY INVISIBLE (7265 3692);
FORCEPROP 2 LAST SIG_NAME NC_M2_0_SUSCLK
J 0
(7215 3660);
DISPLAY 0.680851 (7215 3660);
PAINT WHITE (7215 3660);
WIRE 16 -1 (10575 3900)(9325 3900);
FORCEPROP 2 LAST SIG_NAME P3E_PCH_M2_RX_DP<3>
J 0
(9515 3910);
DISPLAY 0.680851 (9515 3910);
PAINT WHITE (9515 3910);
WIRE 16 -1 (10300 1025)(10300 1175);
WIRE 16 -1 (10300 1175)(11450 1175);
FORCEPROP 2 LAST SIG_NAME LED_HDD_ACTIVITY_B_N
J 0
(10590 1200);
DISPLAY 0.808511 (10590 1200);
PAINT WHITE (10590 1200);
WIRE 16 -1 (9600 1175)(10300 1175);
WIRE 16 -1 (6975 3825)(6975 3350);
WIRE 16 -1 (6975 3350)(8125 3350);
FORCEPROP 2 LAST SIG_NAME M2_SSD0_CLKREQ_EN_N_BUF
J 0
(7215 3360);
DISPLAY 0.702128 (7215 3360);
PAINT WHITE (7215 3360);
WIRE 16 -1 (6525 3350)(6975 3350);
WIRE 16 -1 (7075 3300)(8125 3300);
FORCEPROP 0 LAST CDS_PHYS_NET_NAME NC_M2_1_PEWAKE_N
J 0
(7265 3342);
PAINT MONO (7265 3342);
DISPLAY INVISIBLE (7265 3342);
FORCEPROP 2 LAST SIG_NAME M2_0_PEWAKE_N
J 0
(7415 3310);
DISPLAY 0.680851 (7415 3310);
PAINT WHITE (7415 3310);
WIRE 16 -1 (11275 4375)(11275 4475);
WIRE 16 -1 (11275 4475)(11675 4475);
WIRE 16 -1 (11675 4375)(11675 4475);
WIRE 16 -1 (11675 4475)(12075 4475);
WIRE 16 -1 (12075 4375)(12075 4475);
WIRE 16 -1 (12075 4475)(12475 4475);
WIRE 16 -1 (12475 4475)(12475 4375);
WIRE 16 -1 (12475 4475)(12875 4475);
WIRE 16 -1 (12875 4475)(12875 4375);
WIRE 16 -1 (12875 4475)(13275 4475);
WIRE 16 -1 (13275 4475)(13275 4375);
WIRE 16 -1 (9325 4400)(9475 4400);
WIRE 16 -1 (9325 4350)(9475 4350);
WIRE 16 -1 (9475 4400)(9475 4350);
WIRE 16 -1 (9325 4300)(9475 4300);
WIRE 16 -1 (9475 4350)(9475 4300);
WIRE 16 -1 (9325 4250)(9475 4250);
WIRE 16 -1 (9475 4300)(9475 4250);
WIRE 16 -1 (9325 4200)(9475 4200);
WIRE 16 -1 (9475 4250)(9475 4200);
WIRE 16 -1 (9325 4150)(9475 4150);
WIRE 16 -1 (9475 4200)(9475 4150);
WIRE 16 -1 (9325 4100)(9475 4100);
WIRE 16 -1 (9475 4150)(9475 4100);
WIRE 16 -1 (9325 4050)(9475 4050);
WIRE 16 -1 (9475 4100)(9475 4050);
WIRE 16 -1 (9475 4050)(9475 4000);
WIRE 16 -1 (9325 4000)(9475 4000);
WIRE 16 2175 (8425 800)(8825 800);
WIRE 16 2175 (8825 800)(8825 500);
WIRE 16 2175 (8425 800)(8425 500);
WIRE 16 2175 (8425 500)(8825 500);
WIRE 16 -1 (10725 -350)(10725 -450);
WIRE 16 -1 (10725 -450)(11050 -450);
WIRE 16 -1 (8000 -450)(10725 -450);
FORCEPROP 0 LAST CDS_PHYS_NET_NAME RST_PCIE_CPU0_BUF_E1S_0_PERST_N
J 0
(8025 -408);
PAINT MONO (8025 -408);
DISPLAY INVISIBLE (8025 -408);
FORCEPROP 0 LAST SIG_NAME RST_PCIE_PCH_DEV_BUF_M2_0_PERST_N
J 0
(8190 -440);
DISPLAY 0.702128 (8190 -440);
PAINT WHITE (8190 -440);
WIRE 16 2175 (10950 -575)(11575 -575);
WIRE 16 2175 (11575 -300)(11575 -575);
WIRE 16 2175 (10950 -300)(10950 -575);
WIRE 16 2175 (10950 -300)(11575 -300);
WIRE 16 -1 (11250 -450)(12475 -450);
FORCEPROP 2 LAST SIG_NAME RST_PCIE_PCH_DEV_0_N
J 0
(11640 -440);
DISPLAY 0.702128 (11640 -440);
PAINT WHITE (11640 -440);
WIRE 16 2175 (10450 625)(10925 625);
WIRE 16 2175 (10925 900)(10925 625);
WIRE 16 2175 (10450 900)(10450 625);
WIRE 16 2175 (10450 900)(10925 900);
WIRE 16 -1 (7975 2300)(8125 2300);
WIRE 16 -1 (7975 2300)(7975 2450);
WIRE 16 -1 (7975 2450)(8125 2450);
WIRE 16 -1 (7975 2500)(7975 2450);
WIRE 16 -1 (7975 2500)(8125 2500);
WIRE 16 -1 (7975 2550)(7975 2500);
WIRE 16 -1 (7975 2550)(8125 2550);
WIRE 16 -1 (7975 2600)(7975 2550);
WIRE 16 -1 (7975 2600)(8125 2600);
WIRE 16 -1 (7975 2650)(7975 2600);
WIRE 16 -1 (7975 2650)(8125 2650);
WIRE 16 -1 (7975 2700)(7975 2650);
WIRE 16 -1 (7975 2700)(8125 2700);
WIRE 16 -1 (7975 2750)(7975 2700);
WIRE 16 -1 (7975 2750)(8125 2750);
WIRE 16 -1 (7975 2800)(7975 2750);
WIRE 16 -1 (7975 2800)(8125 2800);
WIRE 16 -1 (7975 2800)(7975 2850);
WIRE 16 -1 (7975 2850)(8125 2850);
WIRE 16 -1 (7975 2850)(7975 2900);
WIRE 16 -1 (7975 2900)(8125 2900);
WIRE 16 -1 (7975 2900)(7975 2950);
WIRE 16 -1 (7975 2950)(8125 2950);
WIRE 16 -1 (7975 2950)(7975 3000);
WIRE 16 -1 (7975 3000)(8125 3000);
WIRE 16 -1 (7975 3000)(7975 3050);
WIRE 16 -1 (7975 3050)(8125 3050);
WIRE 16 -1 (7250 -400)(7350 -400);
WIRE 16 -1 (12875 4175)(12875 4025);
WIRE 16 -1 (12475 4025)(12875 4025);
WIRE 16 -1 (12475 4175)(12475 4025);
WIRE 16 -1 (12075 4175)(12075 4025);
WIRE 16 -1 (12075 4025)(12475 4025);
WIRE 16 -1 (11675 4025)(12075 4025);
WIRE 16 -1 (11675 4175)(11675 4025);
WIRE 16 -1 (11275 4025)(11675 4025);
WIRE 16 -1 (11275 4175)(11275 4025);
WIRE 16 -1 (10725 400)(10725 250);
WIRE 16 -1 (10725 250)(10900 250);
WIRE 16 -1 (10725 250)(9850 250);
FORCEPROP 2 LAST SIG_NAME HDD_ACTIVITY_BUF_N
J 0
(9915 260);
DISPLAY 0.808511 (9915 260);
PAINT WHITE (9915 260);
WIRE 16 -1 (9850 150)(9850 250);
WIRE 16 -1 (6925 3150)(8125 3150);
FORCEPROP 2 LAST SIG_NAME CLK_100M_PE_M2_0_DN
J 0
(7215 3160);
DISPLAY 0.680851 (7215 3160);
PAINT WHITE (7215 3160);
WIRE 16 -1 (8125 3450)(6525 3450);
FORCEPROP 0 LAST CDS_PHYS_NET_NAME RST_PCIE_PCH_DEV_0_N
J 0
(6715 3492);
PAINT MONO (6715 3492);
DISPLAY INVISIBLE (6715 3492);
FORCEPROP 2 LAST SIG_NAME RST_PCIE_PCH_DEV_0_N
J 0
(7215 3460);
DISPLAY 0.680851 (7215 3460);
PAINT WHITE (7215 3460);
WIRE 16 -1 (8125 3550)(6925 3550);
FORCEPROP 0 LAST CDS_PHYS_NET_NAME NC_M2_1_SUSCLK
J 0
(7265 3592);
PAINT MONO (7265 3592);
DISPLAY INVISIBLE (7265 3592);
FORCEPROP 2 LAST SIG_NAME PD_M2_0_DEVSLP
J 0
(7215 3560);
DISPLAY 0.680851 (7215 3560);
PAINT WHITE (7215 3560);
WIRE 16 -1 (10575 3850)(9325 3850);
FORCEPROP 2 LAST SIG_NAME P3E_PCH_M2_RX_DN<3>
J 0
(9515 3860);
DISPLAY 0.680851 (9515 3860);
PAINT WHITE (9515 3860);
WIRE 16 -1 (10575 3700)(9325 3700);
FORCEPROP 2 LAST SIG_NAME P3E_PCH_M2_TX_C_DP<3>
J 0
(9515 3710);
DISPLAY 0.680851 (9515 3710);
PAINT WHITE (9515 3710);
WIRE 16 -1 (9325 3350)(10125 3350);
FORCEPROP 2 LAST SIG_NAME NC_M2_0_NC19
J 0
(9515 3360);
DISPLAY 0.680851 (9515 3360);
PAINT WHITE (9515 3360);
WIRE 16 -1 (9325 3300)(10125 3300);
FORCEPROP 2 LAST SIG_NAME NC_M2_0_NC18
J 0
(9515 3310);
DISPLAY 0.680851 (9515 3310);
PAINT WHITE (9515 3310);
WIRE 16 -1 (9325 3250)(10125 3250);
FORCEPROP 2 LAST SIG_NAME NC_M2_0_NC17
J 0
(9515 3260);
DISPLAY 0.680851 (9515 3260);
PAINT WHITE (9515 3260);
WIRE 16 -1 (9325 3200)(10125 3200);
FORCEPROP 2 LAST SIG_NAME NC_M2_0_NC16
J 0
(9515 3210);
DISPLAY 0.680851 (9515 3210);
PAINT WHITE (9515 3210);
WIRE 16 -1 (8625 -100)(9600 -100);
FORCEPROP 2 LAST SIG_NAME HDD_ACTIVITY_BUF
J 0
(8690 -100);
DISPLAY 0.808511 (8690 -100);
PAINT WHITE (8690 -100);
WIRE 16 -1 (8625 200)(8625 -100);
WIRE 16 -1 (8625 -350)(8625 -100);
WIRE 16 -1 (8000 -350)(8625 -350);
WIRE 16 -1 (9425 -825)(9900 -825);
FORCEPROP 2 LAST SIG_NAME NC_Q95_G2
J 0
(9490 -825);
DISPLAY 0.808511 (9490 -825);
PAINT WHITE (9490 -825);
WIRE 16 -1 (9675 -1075)(10150 -1075);
FORCEPROP 2 LAST SIG_NAME NC_Q95_S2
J 0
(9740 -1075);
DISPLAY 0.808511 (9740 -1075);
PAINT WHITE (9740 -1075);
WIRE 16 -1 (10150 -975)(10150 -1075);
WIRE 16 -1 (9675 -500)(10150 -500);
FORCEPROP 2 LAST SIG_NAME NC_Q95_D2
J 0
(9740 -500);
DISPLAY 0.808511 (9740 -500);
PAINT WHITE (9740 -500);
WIRE 16 -1 (10150 -575)(10150 -500);
WIRE 16 -1 (9325 2550)(10125 2550);
FORCEPROP 2 LAST SIG_NAME NC_M2_0_NC3
J 0
(9515 2560);
DISPLAY 0.680851 (9515 2560);
PAINT WHITE (9515 2560);
WIRE 16 -1 (9325 2600)(10125 2600);
FORCEPROP 2 LAST SIG_NAME NC_M2_0_NC4
J 0
(9515 2610);
DISPLAY 0.680851 (9515 2610);
PAINT WHITE (9515 2610);
WIRE 16 -1 (9325 2800)(10125 2800);
FORCEPROP 2 LAST SIG_NAME NC_M2_0_NC8
J 0
(9515 2810);
DISPLAY 0.680851 (9515 2810);
PAINT WHITE (9515 2810);
WIRE 16 -1 (9325 2900)(10125 2900);
FORCEPROP 2 LAST SIG_NAME NC_M2_0_NC10
J 0
(9515 2910);
DISPLAY 0.680851 (9515 2910);
PAINT WHITE (9515 2910);
WIRE 16 -1 (9325 3150)(10125 3150);
FORCEPROP 2 LAST SIG_NAME NC_M2_0_NC15
J 0
(9515 3160);
DISPLAY 0.680851 (9515 3160);
PAINT WHITE (9515 3160);
WIRE 16 -1 (10575 3750)(9325 3750);
FORCEPROP 2 LAST SIG_NAME P3E_PCH_M2_TX_C_DN<3>
J 0
(9515 3760);
DISPLAY 0.680851 (9515 3760);
PAINT WHITE (9515 3760);
WIRE 16 -1 (10575 3050)(9325 3050);
FORCEPROP 0 LAST CDS_PHYS_NET_NAME SMB_M2_P0_3V3AUX_SDA
J 0
(9515 3092);
PAINT MONO (9515 3092);
DISPLAY INVISIBLE (9515 3092);
FORCEPROP 2 LAST SIG_NAME SMB_M2_P0_1V8AUX_SDA
J 0
(9515 3060);
DISPLAY 0.680851 (9515 3060);
PAINT WHITE (9515 3060);
WIRE 16 -1 (9325 3000)(10575 3000);
FORCEPROP 0 LAST CDS_PHYS_NET_NAME SMB_M2_P0_3V3AUX_SCL
J 0
(9515 3042);
PAINT MONO (9515 3042);
DISPLAY INVISIBLE (9515 3042);
FORCEPROP 2 LAST SIG_NAME SMB_M2_P0_1V8AUX_SCL
J 0
(9515 3010);
DISPLAY 0.680851 (9515 3010);
PAINT WHITE (9515 3010);
WIRE 16 -1 (9325 2950)(10125 2950);
FORCEPROP 2 LAST SIG_NAME NC_M2_0_NC11
J 0
(9515 2960);
DISPLAY 0.680851 (9515 2960);
PAINT WHITE (9515 2960);
WIRE 16 -1 (9325 2750)(10125 2750);
FORCEPROP 2 LAST SIG_NAME NC_M2_0_NC7
J 0
(9515 2760);
DISPLAY 0.680851 (9515 2760);
PAINT WHITE (9515 2760);
WIRE 16 -1 (9325 2700)(10125 2700);
FORCEPROP 2 LAST SIG_NAME NC_M2_0_NC6
J 0
(9515 2710);
DISPLAY 0.680851 (9515 2710);
PAINT WHITE (9515 2710);
WIRE 16 -1 (6350 1225)(6975 1225);
FORCEPROP 2 LAST SIG_NAME LED_M2_SSD_0_ACT_N
J 0
(6365 1235);
DISPLAY 0.723404 (6365 1235);
PAINT WHITE (6365 1235);
WIRE 16 -1 (6975 2400)(6925 2400);
WIRE 16 -1 (6975 2600)(6975 2400);
WIRE 16 -1 (8125 2400)(6975 2400);
FORCEPROP 2 LAST SIG_NAME PCIE_M2_SSD0_PRSNT_N
J 0
(7215 2410);
DISPLAY 0.680851 (7215 2410);
PAINT WHITE (7215 2410);
WIRE 16 -1 (7650 1425)(7650 1225);
WIRE 16 -1 (9100 1225)(7650 1225);
FORCEPROP 2 LAST SIG_NAME LED_HDD_ACTIVITY_N
J 0
(8240 1235);
DISPLAY 0.723404 (8240 1235);
PAINT WHITE (8240 1235);
WIRE 16 -1 (7175 1225)(7650 1225);
WIRE 16 -1 (7775 1125)(9100 1125);
FORCEPROP 2 LAST SIG_NAME PU_BUFFER_HDD_ACTIVITY
J 0
(8240 1135);
DISPLAY 0.723404 (8240 1135);
PAINT WHITE (8240 1135);
WIRE 16 2175 (7450 1375)(7850 1375);
WIRE 16 2175 (7850 1900)(7850 1375);
WIRE 16 2175 (7450 1900)(7450 1375);
WIRE 16 2175 (7450 1900)(7850 1900);
WIRE 16 2175 (7875 -275)(8275 -275);
WIRE 16 2175 (8275 25)(8275 -275);
WIRE 16 2175 (7875 25)(7875 -275);
WIRE 16 2175 (7875 25)(8275 25);
WIRE 16 -1 (6200 -350)(7350 -350);
WIRE 16 -1 (6200 -450)(7350 -450);
FORCEPROP 0 LAST CDS_PHYS_NET_NAME RST_PCIE_CPU0_E1S_PERST_N
J 0
(6225 -408);
PAINT MONO (6225 -408);
DISPLAY INVISIBLE (6225 -408);
FORCEPROP 0 LAST SIG_NAME RST_PCIE_PCH_DEV_PERST_M2_R_N
J 0
(6215 -440);
DISPLAY 0.702128 (6215 -440);
PAINT WHITE (6215 -440);
WIRE 16 -1 (6925 3200)(8125 3200);
FORCEPROP 2 LAST SIG_NAME CLK_100M_PE_M2_0_DP
J 0
(7215 3210);
DISPLAY 0.680851 (7215 3210);
PAINT WHITE (7215 3210);
WIRE 16 -1 (11100 250)(12450 250);
FORCEPROP 2 LAST SIG_NAME PU_BUFFER_HDD_ACTIVITY
J 0
(11515 260);
DISPLAY 0.808511 (11515 260);
PAINT WHITE (11515 260);
WIRE 16 -1 (6225 3300)(6875 3300);
FORCEPROP 0 LAST CDS_PHYS_NET_NAME RST_PCIE_PCH_DEV_PERST_N
J 0
(6715 3336);
PAINT MONO (6715 3336);
DISPLAY INVISIBLE (6715 3336);
FORCEPROP 2 LAST SIG_NAME IRQ_LVC3_WAKE_N
J 0
(6290 3310);
DISPLAY 0.553191 (6290 3310);
PAINT WHITE (6290 3310);
WIRE 16 -1 (5450 3350)(5375 3350);
WIRE 16 -1 (5450 3175)(5450 3350);
WIRE 16 -1 (6325 3350)(5450 3350);
FORCEPROP 2 LAST SIG_NAME M2_SSD0_CLKREQ_EN_N
J 0
(5490 3360);
DISPLAY 0.553191 (5490 3360);
PAINT WHITE (5490 3360);
WIRE 16 -1 (11975 3500)(10700 3500);
FORCEPROP 2 LAST SIG_NAME FM_M2_SSD0_E7_PEDET
J 0
(11190 3510);
DISPLAY 0.680851 (11190 3510);
PAINT WHITE (11190 3510);
WIRE 16 -1 (8125 3850)(7300 3850);
FORCEPROP 0 LAST $PNN P3E_PCH_M2_RX_DN<2>
J 0
(7375 3850);
DISPLAY INVISIBLE (7375 3850);
WIRE 16 2175 (11025 4800)(11550 4800);
WIRE 16 2175 (11550 4800)(11550 4550);
WIRE 16 2175 (11025 4800)(11025 4550);
WIRE 16 2175 (11025 4550)(11550 4550);
WIRE 16 -1 (8125 4100)(7300 4100);
FORCEPROP 0 LAST $PNN P3E_PCH_M2_RX_DN<1>
J 0
(7375 4100);
DISPLAY INVISIBLE (7375 4100);
WIRE 16 -1 (7450 3900)(8125 3900);
WIRE 16 -1 (7775 3750)(8125 3750);
WIRE 16 -1 (7625 3800)(8125 3800);
WIRE 16 -1 (7775 4250)(8125 4250);
WIRE 16 -1 (7625 4300)(8125 4300);
WIRE 16 -1 (7450 4400)(8125 4400);
WIRE 16 -1 (12550 3150)(13350 3150);
FORCEPROP 2 LAST SIG_NAME PD_M2_0_DEVSLP
J 0
(12740 3160);
DISPLAY 0.680851 (12740 3160);
PAINT WHITE (12740 3160);
WIRE 16 -1 (13350 3150)(13350 3000);
DOT 1 (11275 4475);
DOT 1 (10725 -450);
DOT 1 (7975 3000);
DOT 1 (7975 2750);
DOT 1 (7975 2700);
DOT 1 (7975 2650);
DOT 1 (7975 2600);
DOT 1 (7975 2300);
DOT 1 (7975 2250);
DOT 1 (9350 1725);
DOT 1 (10300 1175);
DOT 1 (10725 250);
DOT 1 (7650 1225);
DOT 1 (10300 3500);
DOT 1 (12075 4025);
DOT 1 (9475 4150);
DOT 1 (9475 4100);
DOT 1 (12075 4475);
DOT 1 (11675 4475);
DOT 1 (8050 -400);
DOT 1 (7975 2850);
DOT 1 (9475 4350);
DOT 1 (7975 2550);
DOT 1 (7975 2450);
DOT 1 (13275 4025);
DOT 1 (12875 4025);
DOT 1 (12475 4025);
DOT 1 (12875 4475);
DOT 1 (9475 4400);
DOT 1 (5450 3350);
DOT 1 (7975 2500);
DOT 1 (7975 2950);
DOT 1 (7975 2900);
DOT 1 (6975 3350);
DOT 1 (9475 4200);
DOT 1 (7975 2800);
DOT 1 (8625 -100);
DOT 1 (6975 2400);
DOT 1 (9475 4050);
DOT 1 (12475 4475);
DOT 1 (11675 4025);
DOT 1 (9475 4250);
DOT 1 (9475 4300);
FORCENOTE
TO SCM HDD ACTIVITY LED
(10725 1550) 0;
DISPLAY LEFT (10725 1550);
DISPLAY 1.723404 (10725 1550);
PAINT WHITE (10725 1550);
FORCENOTE
20220818 CHANGE R2113 TO 33.2 OHM
(10950 -275) 0;
DISPLAY LEFT (10950 -275);
DISPLAY 0.893617 (10950 -275);
PAINT WHITE (10950 -275);
FORCENOTE
20211201 PU TO P3V3_AUX
(8000 850) 0;
DISPLAY LEFT (8000 850);
DISPLAY 1.106383 (8000 850);
PAINT WHITE (8000 850);
FORCENOTE
20211201 PU TO P3V3_AUX
(10450 925) 0;
DISPLAY LEFT (10450 925);
DISPLAY 1.106383 (10450 925);
PAINT WHITE (10450 925);
FORCENOTE
20211201 PU TO P3V3_M2_0
(7050 1950) 0;
DISPLAY LEFT (7050 1950);
DISPLAY 1.106383 (7050 1950);
PAINT WHITE (7050 1950);
FORCENOTE
20211201 PU TO P3V3_AUX
(7225 50) 0;
DISPLAY LEFT (7225 50);
DISPLAY 1.106383 (7225 50);
PAINT WHITE (7225 50);
FORCENOTE
20210904 MODIFY FOR GT
(7450 5025) 0;
DISPLAY LEFT (7450 5025);
DISPLAY 2.510638 (7450 5025);
PAINT PINK (7450 5025);
FORCENOTE
20211130 CHANGE TO P3V3_M2_0
(10500 4850) 0;
DISPLAY LEFT (10500 4850);
DISPLAY 1.276596 (10500 4850);
PAINT PINK (10500 4850);
QUIT
